(kicad_sch
	(version 20250114)
	(generator "eeschema")
	(generator_version "9.0")
	(paper "A3")
	(title_block
		(title "Kintex 410T devboard")
		(date "2024-04-03")
		(rev "1.1.2")
	)
	(junction
		(at 157.48 59.69)
		(diameter 0)
		(color 0 0 0 0)
	)
	(junction
		(at 165.1 69.85)
		(diameter 0)
		(color 0 0 0 0)
	)
	(junction
		(at 127 69.85)
		(diameter 0)
		(color 0 0 0 0)
	)
	(junction
		(at 149.86 69.85)
		(diameter 0)
		(color 0 0 0 0)
	)
	(junction
		(at 260.35 69.85)
		(diameter 0)
		(color 0 0 0 0)
	)
	(junction
		(at 142.24 59.69)
		(diameter 0)
		(color 0 0 0 0)
	)
	(junction
		(at 134.62 59.69)
		(diameter 0)
		(color 0 0 0 0)
	)
	(junction
		(at 149.86 59.69)
		(diameter 0)
		(color 0 0 0 0)
	)
	(junction
		(at 267.97 69.85)
		(diameter 0)
		(color 0 0 0 0)
	)
	(junction
		(at 165.1 59.69)
		(diameter 0)
		(color 0 0 0 0)
	)
	(junction
		(at 157.48 69.85)
		(diameter 0)
		(color 0 0 0 0)
	)
	(junction
		(at 134.62 69.85)
		(diameter 0)
		(color 0 0 0 0)
	)
	(junction
		(at 283.21 69.85)
		(diameter 0)
		(color 0 0 0 0)
	)
	(junction
		(at 275.59 59.69)
		(diameter 0)
		(color 0 0 0 0)
	)
	(junction
		(at 127 59.69)
		(diameter 0)
		(color 0 0 0 0)
	)
	(junction
		(at 172.72 59.69)
		(diameter 0)
		(color 0 0 0 0)
	)
	(junction
		(at 252.73 59.69)
		(diameter 0)
		(color 0 0 0 0)
	)
	(junction
		(at 267.97 59.69)
		(diameter 0)
		(color 0 0 0 0)
	)
	(junction
		(at 283.21 59.69)
		(diameter 0)
		(color 0 0 0 0)
	)
	(junction
		(at 237.49 59.69)
		(diameter 0)
		(color 0 0 0 0)
	)
	(junction
		(at 275.59 69.85)
		(diameter 0)
		(color 0 0 0 0)
	)
	(junction
		(at 142.24 69.85)
		(diameter 0)
		(color 0 0 0 0)
	)
	(junction
		(at 260.35 59.69)
		(diameter 0)
		(color 0 0 0 0)
	)
	(junction
		(at 245.11 69.85)
		(diameter 0)
		(color 0 0 0 0)
	)
	(junction
		(at 252.73 69.85)
		(diameter 0)
		(color 0 0 0 0)
	)
	(junction
		(at 245.11 59.69)
		(diameter 0)
		(color 0 0 0 0)
	)
	(no_connect
		(at 231.14 132.08)
	)
	(no_connect
		(at 231.14 142.24)
	)
	(no_connect
		(at 231.14 137.16)
	)
	(no_connect
		(at 231.14 139.7)
	)
	(no_connect
		(at 231.14 134.62)
	)
	(no_connect
		(at 231.14 93.98)
	)
	(no_connect
		(at 231.14 96.52)
	)
	(no_connect
		(at 231.14 104.14)
	)
	(no_connect
		(at 231.14 106.68)
	)
	(no_connect
		(at 231.14 109.22)
	)
	(no_connect
		(at 231.14 119.38)
	)
	(no_connect
		(at 231.14 124.46)
	)
	(no_connect
		(at 231.14 127)
	)
	(no_connect
		(at 231.14 129.54)
	)
	(no_connect
		(at 231.14 147.32)
	)
	(no_connect
		(at 231.14 160.02)
	)
	(no_connect
		(at 231.14 149.86)
	)
	(no_connect
		(at 231.14 152.4)
	)
	(no_connect
		(at 231.14 162.56)
	)
	(no_connect
		(at 231.14 175.26)
	)
	(no_connect
		(at 231.14 167.64)
	)
	(no_connect
		(at 231.14 180.34)
	)
	(no_connect
		(at 231.14 185.42)
	)
	(no_connect
		(at 231.14 200.66)
	)
	(no_connect
		(at 231.14 195.58)
	)
	(no_connect
		(at 231.14 187.96)
	)
	(no_connect
		(at 231.14 215.9)
	)
	(no_connect
		(at 231.14 213.36)
	)
	(no_connect
		(at 231.14 205.74)
	)
	(no_connect
		(at 231.14 210.82)
	)
	(bus_entry
		(at 250.19 198.12)
		(size 1.27 1.27)
		(stroke
			(width 0)
			(type default)
		)
	)
	(bus_entry
		(at 162.56 127)
		(size -1.27 -1.27)
		(stroke
			(width 0)
			(type default)
		)
	)
	(bus_entry
		(at 162.56 187.96)
		(size -1.27 -1.27)
		(stroke
			(width 0)
			(type default)
		)
	)
	(bus_entry
		(at 162.56 121.92)
		(size -1.27 -1.27)
		(stroke
			(width 0)
			(type default)
		)
	)
	(bus_entry
		(at 162.56 190.5)
		(size -1.27 -1.27)
		(stroke
			(width 0)
			(type default)
		)
	)
	(bus_entry
		(at 271.78 193.04)
		(size 1.27 -1.27)
		(stroke
			(width 0)
			(type default)
		)
	)
	(bus_entry
		(at 251.46 209.55)
		(size -1.27 -1.27)
		(stroke
			(width 0)
			(type default)
		)
	)
	(bus_entry
		(at 162.56 193.04)
		(size -1.27 -1.27)
		(stroke
			(width 0)
			(type default)
		)
	)
	(bus_entry
		(at 162.56 210.82)
		(size -1.27 -1.27)
		(stroke
			(width 0)
			(type default)
		)
	)
	(bus_entry
		(at 162.56 142.24)
		(size -1.27 -1.27)
		(stroke
			(width 0)
			(type default)
		)
	)
	(bus_entry
		(at 162.56 180.34)
		(size -1.27 -1.27)
		(stroke
			(width 0)
			(type default)
		)
	)
	(bus_entry
		(at 162.56 104.14)
		(size -1.27 -1.27)
		(stroke
			(width 0)
			(type default)
		)
	)
	(bus_entry
		(at 273.05 110.49)
		(size -1.27 1.27)
		(stroke
			(width 0)
			(type default)
		)
	)
	(bus_entry
		(at 271.78 121.92)
		(size 1.27 -1.27)
		(stroke
			(width 0)
			(type default)
		)
	)
	(bus_entry
		(at 162.56 182.88)
		(size -1.27 -1.27)
		(stroke
			(width 0)
			(type default)
		)
	)
	(bus_entry
		(at 162.56 129.54)
		(size -1.27 -1.27)
		(stroke
			(width 0)
			(type default)
		)
	)
	(bus_entry
		(at 162.56 208.28)
		(size -1.27 -1.27)
		(stroke
			(width 0)
			(type default)
		)
	)
	(bus_entry
		(at 162.56 106.68)
		(size -1.27 -1.27)
		(stroke
			(width 0)
			(type default)
		)
	)
	(bus_entry
		(at 250.19 154.94)
		(size 1.27 1.27)
		(stroke
			(width 0)
			(type default)
		)
	)
	(bus_entry
		(at 251.46 166.37)
		(size -1.27 -1.27)
		(stroke
			(width 0)
			(type default)
		)
	)
	(bus_entry
		(at 162.56 109.22)
		(size -1.27 -1.27)
		(stroke
			(width 0)
			(type default)
		)
	)
	(bus_entry
		(at 162.56 91.44)
		(size -1.27 -1.27)
		(stroke
			(width 0)
			(type default)
		)
	)
	(bus_entry
		(at 162.56 93.98)
		(size -1.27 -1.27)
		(stroke
			(width 0)
			(type default)
		)
	)
	(bus_entry
		(at 162.56 200.66)
		(size -1.27 -1.27)
		(stroke
			(width 0)
			(type default)
		)
	)
	(bus_entry
		(at 162.56 114.3)
		(size -1.27 -1.27)
		(stroke
			(width 0)
			(type default)
		)
	)
	(bus_entry
		(at 162.56 132.08)
		(size -1.27 -1.27)
		(stroke
			(width 0)
			(type default)
		)
	)
	(bus_entry
		(at 250.19 144.78)
		(size 1.27 1.27)
		(stroke
			(width 0)
			(type default)
		)
	)
	(bus_entry
		(at 162.56 185.42)
		(size -1.27 -1.27)
		(stroke
			(width 0)
			(type default)
		)
	)
	(bus_entry
		(at 162.56 134.62)
		(size -1.27 -1.27)
		(stroke
			(width 0)
			(type default)
		)
	)
	(bus_entry
		(at 273.05 97.79)
		(size -1.27 1.27)
		(stroke
			(width 0)
			(type default)
		)
	)
	(bus_entry
		(at 162.56 203.2)
		(size -1.27 -1.27)
		(stroke
			(width 0)
			(type default)
		)
	)
	(bus_entry
		(at 271.78 101.6)
		(size 1.27 -1.27)
		(stroke
			(width 0)
			(type default)
		)
	)
	(bus_entry
		(at 162.56 165.1)
		(size -1.27 -1.27)
		(stroke
			(width 0)
			(type default)
		)
	)
	(bus_entry
		(at 162.56 137.16)
		(size -1.27 -1.27)
		(stroke
			(width 0)
			(type default)
		)
	)
	(bus_entry
		(at 162.56 99.06)
		(size -1.27 -1.27)
		(stroke
			(width 0)
			(type default)
		)
	)
	(bus_entry
		(at 162.56 162.56)
		(size -1.27 -1.27)
		(stroke
			(width 0)
			(type default)
		)
	)
	(bus_entry
		(at 162.56 101.6)
		(size -1.27 -1.27)
		(stroke
			(width 0)
			(type default)
		)
	)
	(bus_entry
		(at 162.56 154.94)
		(size -1.27 -1.27)
		(stroke
			(width 0)
			(type default)
		)
	)
	(bus_entry
		(at 162.56 198.12)
		(size -1.27 -1.27)
		(stroke
			(width 0)
			(type default)
		)
	)
	(bus_entry
		(at 162.56 147.32)
		(size -1.27 -1.27)
		(stroke
			(width 0)
			(type default)
		)
	)
	(bus_entry
		(at 162.56 160.02)
		(size -1.27 -1.27)
		(stroke
			(width 0)
			(type default)
		)
	)
	(bus_entry
		(at 271.78 114.3)
		(size 1.27 -1.27)
		(stroke
			(width 0)
			(type default)
		)
	)
	(bus_entry
		(at 162.56 172.72)
		(size -1.27 -1.27)
		(stroke
			(width 0)
			(type default)
		)
	)
	(bus_entry
		(at 162.56 144.78)
		(size -1.27 -1.27)
		(stroke
			(width 0)
			(type default)
		)
	)
	(bus_entry
		(at 273.05 115.57)
		(size -1.27 1.27)
		(stroke
			(width 0)
			(type default)
		)
	)
	(bus_entry
		(at 162.56 149.86)
		(size -1.27 -1.27)
		(stroke
			(width 0)
			(type default)
		)
	)
	(bus_entry
		(at 162.56 175.26)
		(size -1.27 -1.27)
		(stroke
			(width 0)
			(type default)
		)
	)
	(bus_entry
		(at 162.56 96.52)
		(size -1.27 -1.27)
		(stroke
			(width 0)
			(type default)
		)
	)
	(bus_entry
		(at 162.56 124.46)
		(size -1.27 -1.27)
		(stroke
			(width 0)
			(type default)
		)
	)
	(bus_entry
		(at 250.19 177.8)
		(size 1.27 1.27)
		(stroke
			(width 0)
			(type default)
		)
	)
	(bus_entry
		(at 273.05 90.17)
		(size -1.27 1.27)
		(stroke
			(width 0)
			(type default)
		)
	)
	(bus_entry
		(at 251.46 204.47)
		(size -1.27 -1.27)
		(stroke
			(width 0)
			(type default)
		)
	)
	(bus_entry
		(at 250.19 170.18)
		(size 1.27 1.27)
		(stroke
			(width 0)
			(type default)
		)
	)
	(bus_entry
		(at 162.56 213.36)
		(size -1.27 -1.27)
		(stroke
			(width 0)
			(type default)
		)
	)
	(bus_entry
		(at 162.56 139.7)
		(size -1.27 -1.27)
		(stroke
			(width 0)
			(type default)
		)
	)
	(bus_entry
		(at 162.56 177.8)
		(size -1.27 -1.27)
		(stroke
			(width 0)
			(type default)
		)
	)
	(bus_entry
		(at 162.56 152.4)
		(size -1.27 -1.27)
		(stroke
			(width 0)
			(type default)
		)
	)
	(bus_entry
		(at 250.19 157.48)
		(size 1.27 1.27)
		(stroke
			(width 0)
			(type default)
		)
	)
	(bus_entry
		(at 162.56 119.38)
		(size -1.27 -1.27)
		(stroke
			(width 0)
			(type default)
		)
	)
	(bus_entry
		(at 162.56 111.76)
		(size -1.27 -1.27)
		(stroke
			(width 0)
			(type default)
		)
	)
	(bus_entry
		(at 162.56 205.74)
		(size -1.27 -1.27)
		(stroke
			(width 0)
			(type default)
		)
	)
	(bus_entry
		(at 162.56 167.64)
		(size -1.27 -1.27)
		(stroke
			(width 0)
			(type default)
		)
	)
	(bus_entry
		(at 162.56 116.84)
		(size -1.27 -1.27)
		(stroke
			(width 0)
			(type default)
		)
	)
	(bus_entry
		(at 250.19 182.88)
		(size 1.27 1.27)
		(stroke
			(width 0)
			(type default)
		)
	)
	(bus_entry
		(at 162.56 195.58)
		(size -1.27 -1.27)
		(stroke
			(width 0)
			(type default)
		)
	)
	(bus_entry
		(at 162.56 157.48)
		(size -1.27 -1.27)
		(stroke
			(width 0)
			(type default)
		)
	)
	(bus_entry
		(at 162.56 170.18)
		(size -1.27 -1.27)
		(stroke
			(width 0)
			(type default)
		)
	)
	(bus_entry
		(at 250.19 172.72)
		(size 1.27 1.27)
		(stroke
			(width 0)
			(type default)
		)
	)
	(bus_entry
		(at 162.56 215.9)
		(size -1.27 -1.27)
		(stroke
			(width 0)
			(type default)
		)
	)
	(bus_entry
		(at 273.05 189.23)
		(size -1.27 1.27)
		(stroke
			(width 0)
			(type default)
		)
	)
	(wire
		(pts
			(xy 231.14 111.76) (xy 271.78 111.76)
		)
		(stroke
			(width 0)
			(type default)
		)
	)
	(wire
		(pts
			(xy 172.72 69.85) (xy 172.72 67.31)
		)
		(stroke
			(width 0)
			(type default)
		)
	)
	(wire
		(pts
			(xy 165.1 67.31) (xy 165.1 69.85)
		)
		(stroke
			(width 0)
			(type default)
		)
	)
	(wire
		(pts
			(xy 231.14 177.8) (xy 250.19 177.8)
		)
		(stroke
			(width 0)
			(type default)
		)
	)
	(bus
		(pts
			(xy 161.29 181.61) (xy 161.29 184.15)
		)
		(stroke
			(width 0)
			(type default)
		)
	)
	(wire
		(pts
			(xy 177.8 101.6) (xy 162.56 101.6)
		)
		(stroke
			(width 0)
			(type default)
		)
	)
	(wire
		(pts
			(xy 177.8 116.84) (xy 162.56 116.84)
		)
		(stroke
			(width 0)
			(type default)
		)
	)
	(wire
		(pts
			(xy 252.73 59.69) (xy 245.11 59.69)
		)
		(stroke
			(width 0)
			(type default)
		)
	)
	(bus
		(pts
			(xy 161.29 207.01) (xy 161.29 209.55)
		)
		(stroke
			(width 0)
			(type default)
		)
	)
	(wire
		(pts
			(xy 165.1 59.69) (xy 165.1 62.23)
		)
		(stroke
			(width 0)
			(type default)
		)
	)
	(wire
		(pts
			(xy 162.56 185.42) (xy 177.8 185.42)
		)
		(stroke
			(width 0)
			(type default)
		)
	)
	(bus
		(pts
			(xy 251.46 171.45) (xy 251.46 173.99)
		)
		(stroke
			(width 0)
			(type default)
		)
	)
	(bus
		(pts
			(xy 161.29 123.19) (xy 161.29 125.73)
		)
		(stroke
			(width 0)
			(type default)
		)
	)
	(wire
		(pts
			(xy 162.56 190.5) (xy 177.8 190.5)
		)
		(stroke
			(width 0)
			(type default)
		)
	)
	(wire
		(pts
			(xy 157.48 59.69) (xy 157.48 62.23)
		)
		(stroke
			(width 0)
			(type default)
		)
	)
	(wire
		(pts
			(xy 157.48 69.85) (xy 157.48 67.31)
		)
		(stroke
			(width 0)
			(type default)
		)
	)
	(bus
		(pts
			(xy 160.02 88.9) (xy 158.75 88.9)
		)
		(stroke
			(width 0)
			(type default)
		)
	)
	(wire
		(pts
			(xy 162.56 165.1) (xy 177.8 165.1)
		)
		(stroke
			(width 0)
			(type default)
		)
	)
	(bus
		(pts
			(xy 161.29 168.91) (xy 161.29 171.45)
		)
		(stroke
			(width 0)
			(type default)
		)
	)
	(wire
		(pts
			(xy 260.35 69.85) (xy 252.73 69.85)
		)
		(stroke
			(width 0)
			(type default)
		)
	)
	(wire
		(pts
			(xy 231.14 193.04) (xy 271.78 193.04)
		)
		(stroke
			(width 0)
			(type default)
		)
	)
	(wire
		(pts
			(xy 149.86 62.23) (xy 149.86 59.69)
		)
		(stroke
			(width 0)
			(type default)
		)
	)
	(wire
		(pts
			(xy 162.56 129.54) (xy 177.8 129.54)
		)
		(stroke
			(width 0)
			(type default)
		)
	)
	(bus
		(pts
			(xy 273.05 189.23) (xy 273.05 191.77)
		)
		(stroke
			(width 0)
			(type default)
		)
	)
	(wire
		(pts
			(xy 162.56 154.94) (xy 177.8 154.94)
		)
		(stroke
			(width 0)
			(type default)
		)
	)
	(wire
		(pts
			(xy 121.92 57.15) (xy 121.92 59.69)
		)
		(stroke
			(width 0)
			(type default)
		)
	)
	(wire
		(pts
			(xy 267.97 59.69) (xy 260.35 59.69)
		)
		(stroke
			(width 0)
			(type default)
		)
	)
	(bus
		(pts
			(xy 161.29 120.65) (xy 161.29 123.19)
		)
		(stroke
			(width 0)
			(type default)
		)
	)
	(wire
		(pts
			(xy 177.8 215.9) (xy 162.56 215.9)
		)
		(stroke
			(width 0)
			(type default)
		)
	)
	(wire
		(pts
			(xy 231.14 198.12) (xy 250.19 198.12)
		)
		(stroke
			(width 0)
			(type default)
		)
	)
	(wire
		(pts
			(xy 289.56 57.15) (xy 289.56 59.69)
		)
		(stroke
			(width 0)
			(type default)
		)
	)
	(wire
		(pts
			(xy 177.8 157.48) (xy 162.56 157.48)
		)
		(stroke
			(width 0)
			(type default)
		)
	)
	(wire
		(pts
			(xy 231.14 203.2) (xy 250.19 203.2)
		)
		(stroke
			(width 0)
			(type default)
		)
	)
	(wire
		(pts
			(xy 134.62 59.69) (xy 134.62 62.23)
		)
		(stroke
			(width 0)
			(type default)
		)
	)
	(wire
		(pts
			(xy 162.56 193.04) (xy 177.8 193.04)
		)
		(stroke
			(width 0)
			(type default)
		)
	)
	(bus
		(pts
			(xy 161.29 166.37) (xy 161.29 168.91)
		)
		(stroke
			(width 0)
			(type default)
		)
	)
	(wire
		(pts
			(xy 252.73 69.85) (xy 245.11 69.85)
		)
		(stroke
			(width 0)
			(type default)
		)
	)
	(wire
		(pts
			(xy 162.56 93.98) (xy 177.8 93.98)
		)
		(stroke
			(width 0)
			(type default)
		)
	)
	(bus
		(pts
			(xy 161.29 186.69) (xy 161.29 189.23)
		)
		(stroke
			(width 0)
			(type default)
		)
	)
	(wire
		(pts
			(xy 177.8 187.96) (xy 162.56 187.96)
		)
		(stroke
			(width 0)
			(type default)
		)
	)
	(bus
		(pts
			(xy 161.29 158.75) (xy 161.29 161.29)
		)
		(stroke
			(width 0)
			(type default)
		)
	)
	(wire
		(pts
			(xy 162.56 205.74) (xy 177.8 205.74)
		)
		(stroke
			(width 0)
			(type default)
		)
	)
	(bus
		(pts
			(xy 161.29 128.27) (xy 161.29 130.81)
		)
		(stroke
			(width 0)
			(type default)
		)
	)
	(wire
		(pts
			(xy 162.56 200.66) (xy 177.8 200.66)
		)
		(stroke
			(width 0)
			(type default)
		)
	)
	(wire
		(pts
			(xy 231.14 101.6) (xy 271.78 101.6)
		)
		(stroke
			(width 0)
			(type default)
		)
	)
	(bus
		(pts
			(xy 161.29 143.51) (xy 161.29 146.05)
		)
		(stroke
			(width 0)
			(type default)
		)
	)
	(bus
		(pts
			(xy 161.29 194.31) (xy 161.29 196.85)
		)
		(stroke
			(width 0)
			(type default)
		)
	)
	(wire
		(pts
			(xy 162.56 114.3) (xy 177.8 114.3)
		)
		(stroke
			(width 0)
			(type default)
		)
	)
	(wire
		(pts
			(xy 267.97 69.85) (xy 260.35 69.85)
		)
		(stroke
			(width 0)
			(type default)
		)
	)
	(wire
		(pts
			(xy 157.48 59.69) (xy 165.1 59.69)
		)
		(stroke
			(width 0)
			(type default)
		)
	)
	(bus
		(pts
			(xy 161.29 95.25) (xy 161.29 97.79)
		)
		(stroke
			(width 0)
			(type default)
		)
	)
	(bus
		(pts
			(xy 161.29 196.85) (xy 161.29 199.39)
		)
		(stroke
			(width 0)
			(type default)
		)
	)
	(bus
		(pts
			(xy 161.29 191.77) (xy 161.29 194.31)
		)
		(stroke
			(width 0)
			(type default)
		)
	)
	(bus
		(pts
			(xy 273.05 120.65) (xy 273.05 189.23)
		)
		(stroke
			(width 0)
			(type default)
		)
	)
	(wire
		(pts
			(xy 142.24 59.69) (xy 142.24 62.23)
		)
		(stroke
			(width 0)
			(type default)
		)
	)
	(bus
		(pts
			(xy 161.29 184.15) (xy 161.29 186.69)
		)
		(stroke
			(width 0)
			(type default)
		)
	)
	(wire
		(pts
			(xy 260.35 69.85) (xy 260.35 67.31)
		)
		(stroke
			(width 0)
			(type default)
		)
	)
	(wire
		(pts
			(xy 162.56 124.46) (xy 177.8 124.46)
		)
		(stroke
			(width 0)
			(type default)
		)
	)
	(wire
		(pts
			(xy 162.56 172.72) (xy 177.8 172.72)
		)
		(stroke
			(width 0)
			(type default)
		)
	)
	(wire
		(pts
			(xy 127 69.85) (xy 127 67.31)
		)
		(stroke
			(width 0)
			(type default)
		)
	)
	(wire
		(pts
			(xy 245.11 67.31) (xy 245.11 69.85)
		)
		(stroke
			(width 0)
			(type default)
		)
	)
	(wire
		(pts
			(xy 162.56 195.58) (xy 177.8 195.58)
		)
		(stroke
			(width 0)
			(type default)
		)
	)
	(bus
		(pts
			(xy 251.46 158.75) (xy 251.46 166.37)
		)
		(stroke
			(width 0)
			(type default)
		)
	)
	(bus
		(pts
			(xy 251.46 156.21) (xy 251.46 158.75)
		)
		(stroke
			(width 0)
			(type default)
		)
	)
	(wire
		(pts
			(xy 162.56 121.92) (xy 177.8 121.92)
		)
		(stroke
			(width 0)
			(type default)
		)
	)
	(bus
		(pts
			(xy 161.29 146.05) (xy 161.29 148.59)
		)
		(stroke
			(width 0)
			(type default)
		)
	)
	(wire
		(pts
			(xy 162.56 149.86) (xy 177.8 149.86)
		)
		(stroke
			(width 0)
			(type default)
		)
	)
	(wire
		(pts
			(xy 231.14 154.94) (xy 250.19 154.94)
		)
		(stroke
			(width 0)
			(type default)
		)
	)
	(wire
		(pts
			(xy 177.8 160.02) (xy 162.56 160.02)
		)
		(stroke
			(width 0)
			(type default)
		)
	)
	(wire
		(pts
			(xy 127 62.23) (xy 127 59.69)
		)
		(stroke
			(width 0)
			(type default)
		)
	)
	(wire
		(pts
			(xy 237.49 59.69) (xy 233.68 59.69)
		)
		(stroke
			(width 0)
			(type default)
		)
	)
	(wire
		(pts
			(xy 162.56 109.22) (xy 177.8 109.22)
		)
		(stroke
			(width 0)
			(type default)
		)
	)
	(wire
		(pts
			(xy 162.56 175.26) (xy 177.8 175.26)
		)
		(stroke
			(width 0)
			(type default)
		)
	)
	(wire
		(pts
			(xy 162.56 144.78) (xy 177.8 144.78)
		)
		(stroke
			(width 0)
			(type default)
		)
	)
	(bus
		(pts
			(xy 161.29 173.99) (xy 161.29 176.53)
		)
		(stroke
			(width 0)
			(type default)
		)
	)
	(wire
		(pts
			(xy 127 59.69) (xy 134.62 59.69)
		)
		(stroke
			(width 0)
			(type default)
		)
	)
	(wire
		(pts
			(xy 134.62 69.85) (xy 127 69.85)
		)
		(stroke
			(width 0)
			(type default)
		)
	)
	(wire
		(pts
			(xy 162.56 208.28) (xy 177.8 208.28)
		)
		(stroke
			(width 0)
			(type default)
		)
	)
	(wire
		(pts
			(xy 231.14 190.5) (xy 271.78 190.5)
		)
		(stroke
			(width 0)
			(type default)
		)
	)
	(wire
		(pts
			(xy 142.24 59.69) (xy 149.86 59.69)
		)
		(stroke
			(width 0)
			(type default)
		)
	)
	(bus
		(pts
			(xy 161.29 105.41) (xy 161.29 107.95)
		)
		(stroke
			(width 0)
			(type default)
		)
	)
	(wire
		(pts
			(xy 162.56 142.24) (xy 177.8 142.24)
		)
		(stroke
			(width 0)
			(type default)
		)
	)
	(bus
		(pts
			(xy 161.29 204.47) (xy 161.29 207.01)
		)
		(stroke
			(width 0)
			(type default)
		)
	)
	(bus
		(pts
			(xy 161.29 153.67) (xy 161.29 156.21)
		)
		(stroke
			(width 0)
			(type default)
		)
	)
	(wire
		(pts
			(xy 177.8 119.38) (xy 162.56 119.38)
		)
		(stroke
			(width 0)
			(type default)
		)
	)
	(wire
		(pts
			(xy 177.8 198.12) (xy 162.56 198.12)
		)
		(stroke
			(width 0)
			(type default)
		)
	)
	(wire
		(pts
			(xy 162.56 127) (xy 177.8 127)
		)
		(stroke
			(width 0)
			(type default)
		)
	)
	(wire
		(pts
			(xy 165.1 59.69) (xy 172.72 59.69)
		)
		(stroke
			(width 0)
			(type default)
		)
	)
	(wire
		(pts
			(xy 252.73 59.69) (xy 252.73 62.23)
		)
		(stroke
			(width 0)
			(type default)
		)
	)
	(wire
		(pts
			(xy 177.8 139.7) (xy 162.56 139.7)
		)
		(stroke
			(width 0)
			(type default)
		)
	)
	(wire
		(pts
			(xy 177.8 132.08) (xy 162.56 132.08)
		)
		(stroke
			(width 0)
			(type default)
		)
	)
	(wire
		(pts
			(xy 237.49 69.85) (xy 245.11 69.85)
		)
		(stroke
			(width 0)
			(type default)
		)
	)
	(wire
		(pts
			(xy 260.35 59.69) (xy 260.35 62.23)
		)
		(stroke
			(width 0)
			(type default)
		)
	)
	(bus
		(pts
			(xy 161.29 100.33) (xy 161.29 102.87)
		)
		(stroke
			(width 0)
			(type default)
		)
	)
	(wire
		(pts
			(xy 172.72 62.23) (xy 172.72 59.69)
		)
		(stroke
			(width 0)
			(type default)
		)
	)
	(wire
		(pts
			(xy 267.97 67.31) (xy 267.97 69.85)
		)
		(stroke
			(width 0)
			(type default)
		)
	)
	(wire
		(pts
			(xy 252.73 69.85) (xy 252.73 67.31)
		)
		(stroke
			(width 0)
			(type default)
		)
	)
	(bus
		(pts
			(xy 161.29 133.35) (xy 161.29 135.89)
		)
		(stroke
			(width 0)
			(type default)
		)
	)
	(wire
		(pts
			(xy 162.56 182.88) (xy 177.8 182.88)
		)
		(stroke
			(width 0)
			(type default)
		)
	)
	(bus
		(pts
			(xy 273.05 100.33) (xy 273.05 110.49)
		)
		(stroke
			(width 0)
			(type default)
		)
	)
	(bus
		(pts
			(xy 161.29 161.29) (xy 161.29 163.83)
		)
		(stroke
			(width 0)
			(type default)
		)
	)
	(wire
		(pts
			(xy 231.14 91.44) (xy 271.78 91.44)
		)
		(stroke
			(width 0)
			(type default)
		)
	)
	(wire
		(pts
			(xy 157.48 69.85) (xy 165.1 69.85)
		)
		(stroke
			(width 0)
			(type default)
		)
	)
	(bus
		(pts
			(xy 161.29 212.09) (xy 161.29 214.63)
		)
		(stroke
			(width 0)
			(type default)
		)
	)
	(wire
		(pts
			(xy 162.56 167.64) (xy 177.8 167.64)
		)
		(stroke
			(width 0)
			(type default)
		)
	)
	(bus
		(pts
			(xy 161.29 199.39) (xy 161.29 201.93)
		)
		(stroke
			(width 0)
			(type default)
		)
	)
	(wire
		(pts
			(xy 267.97 59.69) (xy 267.97 62.23)
		)
		(stroke
			(width 0)
			(type default)
		)
	)
	(wire
		(pts
			(xy 176.53 59.69) (xy 176.53 87.63)
		)
		(stroke
			(width 0)
			(type default)
		)
	)
	(wire
		(pts
			(xy 177.8 111.76) (xy 162.56 111.76)
		)
		(stroke
			(width 0)
			(type default)
		)
	)
	(bus
		(pts
			(xy 251.46 199.39) (xy 251.46 204.47)
		)
		(stroke
			(width 0)
			(type default)
		)
	)
	(bus
		(pts
			(xy 161.29 179.07) (xy 161.29 181.61)
		)
		(stroke
			(width 0)
			(type default)
		)
	)
	(bus
		(pts
			(xy 161.29 97.79) (xy 161.29 100.33)
		)
		(stroke
			(width 0)
			(type default)
		)
	)
	(bus
		(pts
			(xy 161.29 151.13) (xy 161.29 153.67)
		)
		(stroke
			(width 0)
			(type default)
		)
	)
	(wire
		(pts
			(xy 177.8 137.16) (xy 162.56 137.16)
		)
		(stroke
			(width 0)
			(type default)
		)
	)
	(bus
		(pts
			(xy 161.29 115.57) (xy 161.29 118.11)
		)
		(stroke
			(width 0)
			(type default)
		)
	)
	(wire
		(pts
			(xy 283.21 69.85) (xy 283.21 71.12)
		)
		(stroke
			(width 0)
			(type default)
		)
	)
	(wire
		(pts
			(xy 245.11 59.69) (xy 237.49 59.69)
		)
		(stroke
			(width 0)
			(type default)
		)
	)
	(wire
		(pts
			(xy 162.56 210.82) (xy 177.8 210.82)
		)
		(stroke
			(width 0)
			(type default)
		)
	)
	(bus
		(pts
			(xy 161.29 209.55) (xy 161.29 212.09)
		)
		(stroke
			(width 0)
			(type default)
		)
	)
	(wire
		(pts
			(xy 231.14 99.06) (xy 271.78 99.06)
		)
		(stroke
			(width 0)
			(type default)
		)
	)
	(wire
		(pts
			(xy 233.68 87.63) (xy 233.68 59.69)
		)
		(stroke
			(width 0)
			(type default)
		)
	)
	(wire
		(pts
			(xy 237.49 69.85) (xy 237.49 67.31)
		)
		(stroke
			(width 0)
			(type default)
		)
	)
	(wire
		(pts
			(xy 283.21 69.85) (xy 283.21 67.31)
		)
		(stroke
			(width 0)
			(type default)
		)
	)
	(wire
		(pts
			(xy 275.59 69.85) (xy 275.59 67.31)
		)
		(stroke
			(width 0)
			(type default)
		)
	)
	(bus
		(pts
			(xy 273.05 115.57) (xy 273.05 120.65)
		)
		(stroke
			(width 0)
			(type default)
		)
	)
	(bus
		(pts
			(xy 161.29 140.97) (xy 161.29 143.51)
		)
		(stroke
			(width 0)
			(type default)
		)
	)
	(bus
		(pts
			(xy 251.46 146.05) (xy 251.46 156.21)
		)
		(stroke
			(width 0)
			(type default)
		)
	)
	(bus
		(pts
			(xy 161.29 130.81) (xy 161.29 133.35)
		)
		(stroke
			(width 0)
			(type default)
		)
	)
	(wire
		(pts
			(xy 245.11 59.69) (xy 245.11 62.23)
		)
		(stroke
			(width 0)
			(type default)
		)
	)
	(wire
		(pts
			(xy 283.21 62.23) (xy 283.21 59.69)
		)
		(stroke
			(width 0)
			(type default)
		)
	)
	(bus
		(pts
			(xy 161.29 113.03) (xy 161.29 115.57)
		)
		(stroke
			(width 0)
			(type default)
		)
	)
	(wire
		(pts
			(xy 162.56 104.14) (xy 177.8 104.14)
		)
		(stroke
			(width 0)
			(type default)
		)
	)
	(wire
		(pts
			(xy 134.62 59.69) (xy 142.24 59.69)
		)
		(stroke
			(width 0)
			(type default)
		)
	)
	(wire
		(pts
			(xy 127 69.85) (xy 127 71.12)
		)
		(stroke
			(width 0)
			(type default)
		)
	)
	(wire
		(pts
			(xy 231.14 87.63) (xy 233.68 87.63)
		)
		(stroke
			(width 0)
			(type default)
		)
	)
	(wire
		(pts
			(xy 231.14 182.88) (xy 250.19 182.88)
		)
		(stroke
			(width 0)
			(type default)
		)
	)
	(wire
		(pts
			(xy 231.14 172.72) (xy 250.19 172.72)
		)
		(stroke
			(width 0)
			(type default)
		)
	)
	(bus
		(pts
			(xy 161.29 135.89) (xy 161.29 138.43)
		)
		(stroke
			(width 0)
			(type default)
		)
	)
	(wire
		(pts
			(xy 142.24 69.85) (xy 149.86 69.85)
		)
		(stroke
			(width 0)
			(type default)
		)
	)
	(bus
		(pts
			(xy 252.73 214.63) (xy 259.08 214.63)
		)
		(stroke
			(width 0)
			(type default)
		)
	)
	(wire
		(pts
			(xy 149.86 69.85) (xy 149.86 67.31)
		)
		(stroke
			(width 0)
			(type default)
		)
	)
	(bus
		(pts
			(xy 251.46 173.99) (xy 251.46 179.07)
		)
		(stroke
			(width 0)
			(type default)
		)
	)
	(bus
		(pts
			(xy 251.46 184.15) (xy 251.46 199.39)
		)
		(stroke
			(width 0)
			(type default)
		)
	)
	(wire
		(pts
			(xy 162.56 147.32) (xy 177.8 147.32)
		)
		(stroke
			(width 0)
			(type default)
		)
	)
	(bus
		(pts
			(xy 251.46 209.55) (xy 251.46 213.36)
		)
		(stroke
			(width 0)
			(type default)
		)
	)
	(bus
		(pts
			(xy 273.05 113.03) (xy 273.05 115.57)
		)
		(stroke
			(width 0)
			(type default)
		)
	)
	(bus
		(pts
			(xy 161.29 148.59) (xy 161.29 151.13)
		)
		(stroke
			(width 0)
			(type default)
		)
	)
	(bus
		(pts
			(xy 161.29 171.45) (xy 161.29 173.99)
		)
		(stroke
			(width 0)
			(type default)
		)
	)
	(wire
		(pts
			(xy 177.8 170.18) (xy 162.56 170.18)
		)
		(stroke
			(width 0)
			(type default)
		)
	)
	(bus
		(pts
			(xy 161.29 176.53) (xy 161.29 179.07)
		)
		(stroke
			(width 0)
			(type default)
		)
	)
	(wire
		(pts
			(xy 142.24 67.31) (xy 142.24 69.85)
		)
		(stroke
			(width 0)
			(type default)
		)
	)
	(bus
		(pts
			(xy 161.29 110.49) (xy 161.29 113.03)
		)
		(stroke
			(width 0)
			(type default)
		)
	)
	(wire
		(pts
			(xy 162.56 213.36) (xy 177.8 213.36)
		)
		(stroke
			(width 0)
			(type default)
		)
	)
	(bus
		(pts
			(xy 161.29 107.95) (xy 161.29 110.49)
		)
		(stroke
			(width 0)
			(type default)
		)
	)
	(bus
		(pts
			(xy 161.29 189.23) (xy 161.29 191.77)
		)
		(stroke
			(width 0)
			(type default)
		)
	)
	(wire
		(pts
			(xy 231.14 114.3) (xy 271.78 114.3)
		)
		(stroke
			(width 0)
			(type default)
		)
	)
	(wire
		(pts
			(xy 237.49 59.69) (xy 237.49 62.23)
		)
		(stroke
			(width 0)
			(type default)
		)
	)
	(wire
		(pts
			(xy 162.56 106.68) (xy 177.8 106.68)
		)
		(stroke
			(width 0)
			(type default)
		)
	)
	(wire
		(pts
			(xy 231.14 116.84) (xy 271.78 116.84)
		)
		(stroke
			(width 0)
			(type default)
		)
	)
	(bus
		(pts
			(xy 273.05 86.36) (xy 274.32 85.09)
		)
		(stroke
			(width 0)
			(type default)
		)
	)
	(bus
		(pts
			(xy 161.29 90.17) (xy 161.29 92.71)
		)
		(stroke
			(width 0)
			(type default)
		)
	)
	(bus
		(pts
			(xy 251.46 166.37) (xy 251.46 171.45)
		)
		(stroke
			(width 0)
			(type default)
		)
	)
	(wire
		(pts
			(xy 283.21 59.69) (xy 289.56 59.69)
		)
		(stroke
			(width 0)
			(type default)
		)
	)
	(wire
		(pts
			(xy 275.59 59.69) (xy 267.97 59.69)
		)
		(stroke
			(width 0)
			(type default)
		)
	)
	(wire
		(pts
			(xy 162.56 152.4) (xy 177.8 152.4)
		)
		(stroke
			(width 0)
			(type default)
		)
	)
	(bus
		(pts
			(xy 161.29 138.43) (xy 161.29 140.97)
		)
		(stroke
			(width 0)
			(type default)
		)
	)
	(bus
		(pts
			(xy 161.29 92.71) (xy 161.29 95.25)
		)
		(stroke
			(width 0)
			(type default)
		)
	)
	(bus
		(pts
			(xy 161.29 118.11) (xy 161.29 120.65)
		)
		(stroke
			(width 0)
			(type default)
		)
	)
	(wire
		(pts
			(xy 172.72 69.85) (xy 165.1 69.85)
		)
		(stroke
			(width 0)
			(type default)
		)
	)
	(bus
		(pts
			(xy 161.29 156.21) (xy 161.29 158.75)
		)
		(stroke
			(width 0)
			(type default)
		)
	)
	(wire
		(pts
			(xy 162.56 134.62) (xy 177.8 134.62)
		)
		(stroke
			(width 0)
			(type default)
		)
	)
	(wire
		(pts
			(xy 231.14 170.18) (xy 250.19 170.18)
		)
		(stroke
			(width 0)
			(type default)
		)
	)
	(wire
		(pts
			(xy 162.56 177.8) (xy 177.8 177.8)
		)
		(stroke
			(width 0)
			(type default)
		)
	)
	(wire
		(pts
			(xy 127 59.69) (xy 121.92 59.69)
		)
		(stroke
			(width 0)
			(type default)
		)
	)
	(bus
		(pts
			(xy 251.46 213.36) (xy 252.73 214.63)
		)
		(stroke
			(width 0)
			(type default)
		)
	)
	(wire
		(pts
			(xy 231.14 144.78) (xy 250.19 144.78)
		)
		(stroke
			(width 0)
			(type default)
		)
	)
	(wire
		(pts
			(xy 260.35 59.69) (xy 252.73 59.69)
		)
		(stroke
			(width 0)
			(type default)
		)
	)
	(wire
		(pts
			(xy 231.14 157.48) (xy 250.19 157.48)
		)
		(stroke
			(width 0)
			(type default)
		)
	)
	(wire
		(pts
			(xy 149.86 59.69) (xy 157.48 59.69)
		)
		(stroke
			(width 0)
			(type default)
		)
	)
	(wire
		(pts
			(xy 176.53 87.63) (xy 177.8 87.63)
		)
		(stroke
			(width 0)
			(type default)
		)
	)
	(bus
		(pts
			(xy 273.05 90.17) (xy 273.05 97.79)
		)
		(stroke
			(width 0)
			(type default)
		)
	)
	(wire
		(pts
			(xy 283.21 59.69) (xy 275.59 59.69)
		)
		(stroke
			(width 0)
			(type default)
		)
	)
	(wire
		(pts
			(xy 134.62 69.85) (xy 142.24 69.85)
		)
		(stroke
			(width 0)
			(type default)
		)
	)
	(bus
		(pts
			(xy 161.29 102.87) (xy 161.29 105.41)
		)
		(stroke
			(width 0)
			(type default)
		)
	)
	(bus
		(pts
			(xy 251.46 179.07) (xy 251.46 184.15)
		)
		(stroke
			(width 0)
			(type default)
		)
	)
	(bus
		(pts
			(xy 161.29 90.17) (xy 160.02 88.9)
		)
		(stroke
			(width 0)
			(type default)
		)
	)
	(bus
		(pts
			(xy 161.29 163.83) (xy 161.29 166.37)
		)
		(stroke
			(width 0)
			(type default)
		)
	)
	(wire
		(pts
			(xy 231.14 165.1) (xy 250.19 165.1)
		)
		(stroke
			(width 0)
			(type default)
		)
	)
	(wire
		(pts
			(xy 177.8 203.2) (xy 162.56 203.2)
		)
		(stroke
			(width 0)
			(type default)
		)
	)
	(bus
		(pts
			(xy 161.29 125.73) (xy 161.29 128.27)
		)
		(stroke
			(width 0)
			(type default)
		)
	)
	(bus
		(pts
			(xy 273.05 110.49) (xy 273.05 113.03)
		)
		(stroke
			(width 0)
			(type default)
		)
	)
	(wire
		(pts
			(xy 231.14 208.28) (xy 250.19 208.28)
		)
		(stroke
			(width 0)
			(type default)
		)
	)
	(wire
		(pts
			(xy 162.56 96.52) (xy 177.8 96.52)
		)
		(stroke
			(width 0)
			(type default)
		)
	)
	(bus
		(pts
			(xy 251.46 204.47) (xy 251.46 209.55)
		)
		(stroke
			(width 0)
			(type default)
		)
	)
	(wire
		(pts
			(xy 149.86 69.85) (xy 157.48 69.85)
		)
		(stroke
			(width 0)
			(type default)
		)
	)
	(wire
		(pts
			(xy 134.62 69.85) (xy 134.62 67.31)
		)
		(stroke
			(width 0)
			(type default)
		)
	)
	(bus
		(pts
			(xy 273.05 90.17) (xy 273.05 86.36)
		)
		(stroke
			(width 0)
			(type default)
		)
	)
	(wire
		(pts
			(xy 162.56 180.34) (xy 177.8 180.34)
		)
		(stroke
			(width 0)
			(type default)
		)
	)
	(bus
		(pts
			(xy 273.05 97.79) (xy 273.05 100.33)
		)
		(stroke
			(width 0)
			(type default)
		)
	)
	(wire
		(pts
			(xy 162.56 91.44) (xy 177.8 91.44)
		)
		(stroke
			(width 0)
			(type default)
		)
	)
	(wire
		(pts
			(xy 275.59 69.85) (xy 267.97 69.85)
		)
		(stroke
			(width 0)
			(type default)
		)
	)
	(wire
		(pts
			(xy 172.72 59.69) (xy 176.53 59.69)
		)
		(stroke
			(width 0)
			(type default)
		)
	)
	(wire
		(pts
			(xy 231.14 121.92) (xy 271.78 121.92)
		)
		(stroke
			(width 0)
			(type default)
		)
	)
	(wire
		(pts
			(xy 162.56 162.56) (xy 177.8 162.56)
		)
		(stroke
			(width 0)
			(type default)
		)
	)
	(wire
		(pts
			(xy 275.59 59.69) (xy 275.59 62.23)
		)
		(stroke
			(width 0)
			(type default)
		)
	)
	(wire
		(pts
			(xy 162.56 99.06) (xy 177.8 99.06)
		)
		(stroke
			(width 0)
			(type default)
		)
	)
	(bus
		(pts
			(xy 161.29 201.93) (xy 161.29 204.47)
		)
		(stroke
			(width 0)
			(type default)
		)
	)
	(wire
		(pts
			(xy 275.59 69.85) (xy 283.21 69.85)
		)
		(stroke
			(width 0)
			(type default)
		)
	)
	(bus
		(pts
			(xy 274.32 85.09) (xy 280.67 85.09)
		)
		(stroke
			(width 0)
			(type default)
		)
	)
	(label "FMC.IO22_N"
		(at 173.99 203.2 180)
		(effects
			(font
				(size 1.27 1.27)
			)
			(justify right bottom)
		)
	)
	(label "FMC.IO18_N"
		(at 173.99 182.88 180)
		(effects
			(font
				(size 1.27 1.27)
			)
			(justify right bottom)
		)
	)
	(label "ETH_RMII.MDIO"
		(at 233.68 170.18 0)
		(effects
			(font
				(size 1.27 1.27)
			)
			(justify left bottom)
		)
	)
	(label "FMC.IO4_P"
		(at 173.99 109.22 180)
		(effects
			(font
				(size 1.27 1.27)
			)
			(justify right bottom)
		)
	)
	(label "FMC.IO19_N"
		(at 173.99 187.96 180)
		(effects
			(font
				(size 1.27 1.27)
			)
			(justify right bottom)
		)
	)
	(label "USB_USER.RCV"
		(at 255.27 193.04 0)
		(effects
			(font
				(size 1.27 1.27)
			)
			(justify left bottom)
		)
	)
	(label "FMC.IO22_P"
		(at 173.99 200.66 180)
		(effects
			(font
				(size 1.27 1.27)
			)
			(justify right bottom)
		)
	)
	(label "ETH_RMII.TXEN"
		(at 233.68 208.28 0)
		(effects
			(font
				(size 1.27 1.27)
			)
			(justify left bottom)
		)
	)
	(label "USB_USER.SUS"
		(at 255.27 101.6 0)
		(effects
			(font
				(size 1.27 1.27)
			)
			(justify left bottom)
		)
	)
	(label "FMC.IO1_N"
		(at 173.99 96.52 180)
		(effects
			(font
				(size 1.27 1.27)
			)
			(justify right bottom)
		)
	)
	(label "FMC.IO21_P"
		(at 173.99 195.58 180)
		(effects
			(font
				(size 1.27 1.27)
			)
			(justify right bottom)
		)
	)
	(label "FMC.IO11_P"
		(at 173.99 144.78 180)
		(effects
			(font
				(size 1.27 1.27)
			)
			(justify right bottom)
		)
	)
	(label "FMC.IO3_P"
		(at 173.99 104.14 180)
		(effects
			(font
				(size 1.27 1.27)
			)
			(justify right bottom)
		)
	)
	(label "USB_USER.VP"
		(at 255.27 190.5 0)
		(effects
			(font
				(size 1.27 1.27)
			)
			(justify left bottom)
		)
	)
	(label "FMC.IO23_N"
		(at 173.99 208.28 180)
		(effects
			(font
				(size 1.27 1.27)
			)
			(justify right bottom)
		)
	)
	(label "FMC.IO25"
		(at 173.99 215.9 180)
		(effects
			(font
				(size 1.27 1.27)
			)
			(justify right bottom)
		)
	)
	(label "FMC.IO23_P"
		(at 173.99 205.74 180)
		(effects
			(font
				(size 1.27 1.27)
			)
			(justify right bottom)
		)
	)
	(label "ETH_RMII.MDC"
		(at 233.68 172.72 0)
		(effects
			(font
				(size 1.27 1.27)
			)
			(justify left bottom)
		)
	)
	(label "FMC.IO20_P"
		(at 173.99 190.5 180)
		(effects
			(font
				(size 1.27 1.27)
			)
			(justify right bottom)
		)
	)
	(label "FMC.IO16_P"
		(at 173.99 170.18 180)
		(effects
			(font
				(size 1.27 1.27)
			)
			(justify right bottom)
		)
	)
	(label "FMC.IO8_P"
		(at 173.99 129.54 180)
		(effects
			(font
				(size 1.27 1.27)
			)
			(justify right bottom)
		)
	)
	(label "FMC.IO3_N"
		(at 173.99 106.68 180)
		(effects
			(font
				(size 1.27 1.27)
			)
			(justify right bottom)
		)
	)
	(label "USB_USER.VMO"
		(at 255.27 116.84 0)
		(effects
			(font
				(size 1.27 1.27)
			)
			(justify left bottom)
		)
	)
	(label "FMC.IO18_P"
		(at 173.99 180.34 180)
		(effects
			(font
				(size 1.27 1.27)
			)
			(justify right bottom)
		)
	)
	(label "FMC.IO9_P"
		(at 173.99 134.62 180)
		(effects
			(font
				(size 1.27 1.27)
			)
			(justify right bottom)
		)
	)
	(label "ETH_RMII.RXD1"
		(at 233.68 157.48 0)
		(effects
			(font
				(size 1.27 1.27)
			)
			(justify left bottom)
		)
	)
	(label "ETH_RMII.~{RESET}"
		(at 233.68 154.94 0)
		(effects
			(font
				(size 1.27 1.27)
			)
			(justify left bottom)
		)
	)
	(label "FMC.IO20_N"
		(at 173.99 193.04 180)
		(effects
			(font
				(size 1.27 1.27)
			)
			(justify right bottom)
		)
	)
	(label "FMC.IO7_N"
		(at 173.99 127 180)
		(effects
			(font
				(size 1.27 1.27)
			)
			(justify right bottom)
		)
	)
	(label "FMC.IO12_P"
		(at 173.99 149.86 180)
		(effects
			(font
				(size 1.27 1.27)
			)
			(justify right bottom)
		)
	)
	(label "FMC.IO17_N"
		(at 173.99 177.8 180)
		(effects
			(font
				(size 1.27 1.27)
			)
			(justify right bottom)
		)
	)
	(label "FMC.IO13_P"
		(at 173.99 154.94 180)
		(effects
			(font
				(size 1.27 1.27)
			)
			(justify right bottom)
		)
	)
	(label "FMC.IO24_N"
		(at 173.99 213.36 180)
		(effects
			(font
				(size 1.27 1.27)
			)
			(justify right bottom)
		)
	)
	(label "USB_USER.~{OE}"
		(at 255.27 111.76 0)
		(effects
			(font
				(size 1.27 1.27)
			)
			(justify left bottom)
		)
	)
	(label "FMC.IO5_N"
		(at 173.99 116.84 180)
		(effects
			(font
				(size 1.27 1.27)
			)
			(justify right bottom)
		)
	)
	(label "FMC.IO13_N"
		(at 173.99 157.48 180)
		(effects
			(font
				(size 1.27 1.27)
			)
			(justify right bottom)
		)
	)
	(label "FMC.IO5_P"
		(at 173.99 114.3 180)
		(effects
			(font
				(size 1.27 1.27)
			)
			(justify right bottom)
		)
	)
	(label "ETH_RMII.TXD0"
		(at 233.68 198.12 0)
		(effects
			(font
				(size 1.27 1.27)
			)
			(justify left bottom)
		)
	)
	(label "FMC.IO1_P"
		(at 173.99 93.98 180)
		(effects
			(font
				(size 1.27 1.27)
			)
			(justify right bottom)
		)
	)
	(label "FMC.IO4_N"
		(at 173.99 111.76 180)
		(effects
			(font
				(size 1.27 1.27)
			)
			(justify right bottom)
		)
	)
	(label "FMC.IO2_N"
		(at 173.99 101.6 180)
		(effects
			(font
				(size 1.27 1.27)
			)
			(justify right bottom)
		)
	)
	(label "FMC.IO10_N"
		(at 173.99 142.24 180)
		(effects
			(font
				(size 1.27 1.27)
			)
			(justify right bottom)
		)
	)
	(label "FMC.IO17_P"
		(at 173.99 175.26 180)
		(effects
			(font
				(size 1.27 1.27)
			)
			(justify right bottom)
		)
	)
	(label "FMC.IO11_N"
		(at 173.99 147.32 180)
		(effects
			(font
				(size 1.27 1.27)
			)
			(justify right bottom)
		)
	)
	(label "USB_USER.VPO"
		(at 255.27 114.3 0)
		(effects
			(font
				(size 1.27 1.27)
			)
			(justify left bottom)
		)
	)
	(label "FMC.IO16_N"
		(at 173.99 172.72 180)
		(effects
			(font
				(size 1.27 1.27)
			)
			(justify right bottom)
		)
	)
	(label "ETH_RMII.RX_DV"
		(at 233.68 144.78 0)
		(effects
			(font
				(size 1.27 1.27)
			)
			(justify left bottom)
		)
	)
	(label "ETH_RMII.RXD0"
		(at 233.68 177.8 0)
		(effects
			(font
				(size 1.27 1.27)
			)
			(justify left bottom)
		)
	)
	(label "FMC.IO6_N"
		(at 173.99 121.92 180)
		(effects
			(font
				(size 1.27 1.27)
			)
			(justify right bottom)
		)
	)
	(label "FMC.IO15_N"
		(at 173.99 167.64 180)
		(effects
			(font
				(size 1.27 1.27)
			)
			(justify right bottom)
		)
	)
	(label "FMC.IO24_P"
		(at 173.99 210.82 180)
		(effects
			(font
				(size 1.27 1.27)
			)
			(justify right bottom)
		)
	)
	(label "FMC.IO19_P"
		(at 173.99 185.42 180)
		(effects
			(font
				(size 1.27 1.27)
			)
			(justify right bottom)
		)
	)
	(label "FMC.IO14_N"
		(at 173.99 162.56 180)
		(effects
			(font
				(size 1.27 1.27)
			)
			(justify right bottom)
		)
	)
	(label "USB_USER.SCON"
		(at 255.27 99.06 0)
		(effects
			(font
				(size 1.27 1.27)
			)
			(justify left bottom)
		)
	)
	(label "USB_USER.VM"
		(at 255.27 91.44 0)
		(effects
			(font
				(size 1.27 1.27)
			)
			(justify left bottom)
		)
	)
	(label "FMC.IO8_N"
		(at 173.99 132.08 180)
		(effects
			(font
				(size 1.27 1.27)
			)
			(justify right bottom)
		)
	)
	(label "ETH_RMII.TXD1"
		(at 233.68 203.2 0)
		(effects
			(font
				(size 1.27 1.27)
			)
			(justify left bottom)
		)
	)
	(label "FMC.IO14_P"
		(at 173.99 160.02 180)
		(effects
			(font
				(size 1.27 1.27)
			)
			(justify right bottom)
		)
	)
	(label "FMC.IO9_N"
		(at 173.99 137.16 180)
		(effects
			(font
				(size 1.27 1.27)
			)
			(justify right bottom)
		)
	)
	(label "FMC.IO10_P"
		(at 173.99 139.7 180)
		(effects
			(font
				(size 1.27 1.27)
			)
			(justify right bottom)
		)
	)
	(label "FMC.IO0"
		(at 173.99 91.44 180)
		(effects
			(font
				(size 1.27 1.27)
			)
			(justify right bottom)
		)
	)
	(label "FMC.IO6_P"
		(at 173.99 119.38 180)
		(effects
			(font
				(size 1.27 1.27)
			)
			(justify right bottom)
		)
	)
	(label "USB_USER.SPD"
		(at 255.27 121.92 0)
		(effects
			(font
				(size 1.27 1.27)
			)
			(justify left bottom)
		)
	)
	(label "FMC.IO21_N"
		(at 173.99 198.12 180)
		(effects
			(font
				(size 1.27 1.27)
			)
			(justify right bottom)
		)
	)
	(label "ETH_RMII.RXER"
		(at 233.68 165.1 0)
		(effects
			(font
				(size 1.27 1.27)
			)
			(justify left bottom)
		)
	)
	(label "FMC.IO2_P"
		(at 173.99 99.06 180)
		(effects
			(font
				(size 1.27 1.27)
			)
			(justify right bottom)
		)
	)
	(label "FMC.IO12_N"
		(at 173.99 152.4 180)
		(effects
			(font
				(size 1.27 1.27)
			)
			(justify right bottom)
		)
	)
	(label "FMC.IO15_P"
		(at 173.99 165.1 180)
		(effects
			(font
				(size 1.27 1.27)
			)
			(justify right bottom)
		)
	)
	(label "ETH_RMII.REFCLK"
		(at 233.68 182.88 0)
		(effects
			(font
				(size 1.27 1.27)
			)
			(justify left bottom)
		)
	)
	(label "FMC.IO7_P"
		(at 173.99 124.46 180)
		(effects
			(font
				(size 1.27 1.27)
			)
			(justify right bottom)
		)
	)
	(hierarchical_label "FMC{FMC-IO}"
		(shape bidirectional)
		(at 158.75 88.9 180)
		(effects
			(font
				(size 1.27 1.27)
			)
			(justify right)
		)
	)
	(hierarchical_label "USB_USER{USB-FPGA-PHY}"
		(shape bidirectional)
		(at 280.67 85.09 0)
		(effects
			(font
				(size 1.27 1.27)
			)
			(justify left)
		)
	)
	(hierarchical_label "ETH_RMII{RMII}"
		(shape bidirectional)
		(at 259.08 214.63 0)
		(effects
			(font
				(size 1.27 1.27)
			)
			(justify left)
		)
	)
	(symbol
		(lib_id "antmicroCapacitors0402:C_100n_0402")
		(at 245.11 67.31 90)
		(unit 1)
		(exclude_from_sim no)
		(in_bom yes)
		(on_board yes)
		(dnp no)
		(property "Reference" "C77"
			(at 245.745 62.865 90)
			(effects
				(font
					(size 1.27 1.27)
				)
				(justify right)
			)
		)
		(property "Value" "C_100n_0402"
			(at 255.27 46.99 0)
			(effects
				(font
					(size 1.27 1.27)
					(thickness 0.15)
				)
				(justify left bottom)
				(hide yes)
			)
		)
		(property "Footprint" "antmicro-footprints:C_0402_1005Metric"
			(at 257.81 46.99 0)
			(effects
				(font
					(size 1.27 1.27)
					(thickness 0.15)
				)
				(justify left bottom)
				(hide yes)
			)
		)
		(property "Datasheet" "https://www.murata.com/products/productdetail?partno=GRM155R61H104KE14%23"
			(at 260.35 46.99 0)
			(effects
				(font
					(size 1.27 1.27)
					(thickness 0.15)
				)
				(justify left bottom)
				(hide yes)
			)
		)
		(property "Description" ""
			(at 245.11 67.31 0)
			(effects
				(font
					(size 1.27 1.27)
				)
			)
		)
		(property "Manufacturer" "Murata"
			(at 265.43 46.99 0)
			(effects
				(font
					(size 1.27 1.27)
					(thickness 0.15)
				)
				(justify left bottom)
				(hide yes)
			)
		)
		(property "MPN" "GRM155R61H104KE14D"
			(at 262.89 46.99 0)
			(effects
				(font
					(size 1.27 1.27)
					(thickness 0.15)
				)
				(justify left bottom)
				(hide yes)
			)
		)
		(property "Val" "100n"
			(at 245.745 66.675 90)
			(effects
				(font
					(size 1.27 1.27)
					(thickness 0.15)
				)
				(justify right)
			)
		)
		(property "License" "Apache-2.0"
			(at 267.97 46.99 0)
			(effects
				(font
					(size 1.27 1.27)
					(thickness 0.15)
				)
				(justify left bottom)
				(hide yes)
			)
		)
		(property "Author" "Antmicro"
			(at 270.51 46.99 0)
			(effects
				(font
					(size 1.27 1.27)
					(thickness 0.15)
				)
				(justify left bottom)
				(hide yes)
			)
		)
		(property "Voltage" "50V"
			(at 273.05 46.99 0)
			(effects
				(font
					(size 1.27 1.27)
				)
				(justify left bottom)
				(hide yes)
			)
		)
		(property "Dielectric" "X5R"
			(at 275.59 46.99 0)
			(effects
				(font
					(size 1.27 1.27)
				)
				(justify left bottom)
				(hide yes)
			)
		)
		(pin "1"
		)
		(pin "2"
		)
		(instances
			(project "k410t-devboard"
				(path ""
					(reference "C77")
					(unit 1)
				)
			)
		)
	)
	(symbol
		(lib_id "antmicroCapacitors0402:C_100n_0402")
		(at 267.97 67.31 90)
		(unit 1)
		(exclude_from_sim no)
		(in_bom yes)
		(on_board yes)
		(dnp no)
		(property "Reference" "C94"
			(at 268.605 62.865 90)
			(effects
				(font
					(size 1.27 1.27)
				)
				(justify right)
			)
		)
		(property "Value" "C_100n_0402"
			(at 278.13 46.99 0)
			(effects
				(font
					(size 1.27 1.27)
					(thickness 0.15)
				)
				(justify left bottom)
				(hide yes)
			)
		)
		(property "Footprint" "antmicro-footprints:C_0402_1005Metric"
			(at 280.67 46.99 0)
			(effects
				(font
					(size 1.27 1.27)
					(thickness 0.15)
				)
				(justify left bottom)
				(hide yes)
			)
		)
		(property "Datasheet" "https://www.murata.com/products/productdetail?partno=GRM155R61H104KE14%23"
			(at 283.21 46.99 0)
			(effects
				(font
					(size 1.27 1.27)
					(thickness 0.15)
				)
				(justify left bottom)
				(hide yes)
			)
		)
		(property "Description" ""
			(at 267.97 67.31 0)
			(effects
				(font
					(size 1.27 1.27)
				)
			)
		)
		(property "Manufacturer" "Murata"
			(at 288.29 46.99 0)
			(effects
				(font
					(size 1.27 1.27)
					(thickness 0.15)
				)
				(justify left bottom)
				(hide yes)
			)
		)
		(property "MPN" "GRM155R61H104KE14D"
			(at 285.75 46.99 0)
			(effects
				(font
					(size 1.27 1.27)
					(thickness 0.15)
				)
				(justify left bottom)
				(hide yes)
			)
		)
		(property "Val" "100n"
			(at 268.605 66.675 90)
			(effects
				(font
					(size 1.27 1.27)
					(thickness 0.15)
				)
				(justify right)
			)
		)
		(property "License" "Apache-2.0"
			(at 290.83 46.99 0)
			(effects
				(font
					(size 1.27 1.27)
					(thickness 0.15)
				)
				(justify left bottom)
				(hide yes)
			)
		)
		(property "Author" "Antmicro"
			(at 293.37 46.99 0)
			(effects
				(font
					(size 1.27 1.27)
					(thickness 0.15)
				)
				(justify left bottom)
				(hide yes)
			)
		)
		(property "Voltage" "50V"
			(at 295.91 46.99 0)
			(effects
				(font
					(size 1.27 1.27)
				)
				(justify left bottom)
				(hide yes)
			)
		)
		(property "Dielectric" "X5R"
			(at 298.45 46.99 0)
			(effects
				(font
					(size 1.27 1.27)
				)
				(justify left bottom)
				(hide yes)
			)
		)
		(pin "1"
		)
		(pin "2"
		)
		(instances
			(project "k410t-devboard"
				(path ""
					(reference "C94")
					(unit 1)
				)
			)
		)
	)
	(symbol
		(lib_id "antmicroCapacitors0402:C_100n_0402")
		(at 237.49 67.31 90)
		(unit 1)
		(exclude_from_sim no)
		(in_bom yes)
		(on_board yes)
		(dnp no)
		(property "Reference" "C69"
			(at 238.125 62.865 90)
			(effects
				(font
					(size 1.27 1.27)
				)
				(justify right)
			)
		)
		(property "Value" "C_100n_0402"
			(at 247.65 46.99 0)
			(effects
				(font
					(size 1.27 1.27)
					(thickness 0.15)
				)
				(justify left bottom)
				(hide yes)
			)
		)
		(property "Footprint" "antmicro-footprints:C_0402_1005Metric"
			(at 250.19 46.99 0)
			(effects
				(font
					(size 1.27 1.27)
					(thickness 0.15)
				)
				(justify left bottom)
				(hide yes)
			)
		)
		(property "Datasheet" "https://www.murata.com/products/productdetail?partno=GRM155R61H104KE14%23"
			(at 252.73 46.99 0)
			(effects
				(font
					(size 1.27 1.27)
					(thickness 0.15)
				)
				(justify left bottom)
				(hide yes)
			)
		)
		(property "Description" ""
			(at 237.49 67.31 0)
			(effects
				(font
					(size 1.27 1.27)
				)
			)
		)
		(property "Manufacturer" "Murata"
			(at 257.81 46.99 0)
			(effects
				(font
					(size 1.27 1.27)
					(thickness 0.15)
				)
				(justify left bottom)
				(hide yes)
			)
		)
		(property "MPN" "GRM155R61H104KE14D"
			(at 255.27 46.99 0)
			(effects
				(font
					(size 1.27 1.27)
					(thickness 0.15)
				)
				(justify left bottom)
				(hide yes)
			)
		)
		(property "Val" "100n"
			(at 238.125 66.675 90)
			(effects
				(font
					(size 1.27 1.27)
					(thickness 0.15)
				)
				(justify right)
			)
		)
		(property "License" "Apache-2.0"
			(at 260.35 46.99 0)
			(effects
				(font
					(size 1.27 1.27)
					(thickness 0.15)
				)
				(justify left bottom)
				(hide yes)
			)
		)
		(property "Author" "Antmicro"
			(at 262.89 46.99 0)
			(effects
				(font
					(size 1.27 1.27)
					(thickness 0.15)
				)
				(justify left bottom)
				(hide yes)
			)
		)
		(property "Voltage" "50V"
			(at 265.43 46.99 0)
			(effects
				(font
					(size 1.27 1.27)
				)
				(justify left bottom)
				(hide yes)
			)
		)
		(property "Dielectric" "X5R"
			(at 267.97 46.99 0)
			(effects
				(font
					(size 1.27 1.27)
				)
				(justify left bottom)
				(hide yes)
			)
		)
		(pin "1"
		)
		(pin "2"
		)
		(instances
			(project "k410t-devboard"
				(path ""
					(reference "C69")
					(unit 1)
				)
			)
		)
	)
	(symbol
		(lib_id "antmicroCapacitors0402:C_100n_0402")
		(at 165.1 67.31 270)
		(mirror x)
		(unit 1)
		(exclude_from_sim no)
		(in_bom yes)
		(on_board yes)
		(dnp no)
		(property "Reference" "C76"
			(at 164.465 62.865 90)
			(effects
				(font
					(size 1.27 1.27)
				)
				(justify right)
			)
		)
		(property "Value" "C_100n_0402"
			(at 154.94 46.99 0)
			(effects
				(font
					(size 1.27 1.27)
					(thickness 0.15)
				)
				(justify left bottom)
				(hide yes)
			)
		)
		(property "Footprint" "antmicro-footprints:C_0402_1005Metric"
			(at 152.4 46.99 0)
			(effects
				(font
					(size 1.27 1.27)
					(thickness 0.15)
				)
				(justify left bottom)
				(hide yes)
			)
		)
		(property "Datasheet" "https://www.murata.com/products/productdetail?partno=GRM155R61H104KE14%23"
			(at 149.86 46.99 0)
			(effects
				(font
					(size 1.27 1.27)
					(thickness 0.15)
				)
				(justify left bottom)
				(hide yes)
			)
		)
		(property "Description" ""
			(at 165.1 67.31 0)
			(effects
				(font
					(size 1.27 1.27)
				)
			)
		)
		(property "Manufacturer" "Murata"
			(at 144.78 46.99 0)
			(effects
				(font
					(size 1.27 1.27)
					(thickness 0.15)
				)
				(justify left bottom)
				(hide yes)
			)
		)
		(property "MPN" "GRM155R61H104KE14D"
			(at 147.32 46.99 0)
			(effects
				(font
					(size 1.27 1.27)
					(thickness 0.15)
				)
				(justify left bottom)
				(hide yes)
			)
		)
		(property "Val" "100n"
			(at 164.465 66.675 90)
			(effects
				(font
					(size 1.27 1.27)
					(thickness 0.15)
				)
				(justify right)
			)
		)
		(property "License" "Apache-2.0"
			(at 142.24 46.99 0)
			(effects
				(font
					(size 1.27 1.27)
					(thickness 0.15)
				)
				(justify left bottom)
				(hide yes)
			)
		)
		(property "Author" "Antmicro"
			(at 139.7 46.99 0)
			(effects
				(font
					(size 1.27 1.27)
					(thickness 0.15)
				)
				(justify left bottom)
				(hide yes)
			)
		)
		(property "Voltage" "50V"
			(at 137.16 46.99 0)
			(effects
				(font
					(size 1.27 1.27)
				)
				(justify left bottom)
				(hide yes)
			)
		)
		(property "Dielectric" "X5R"
			(at 134.62 46.99 0)
			(effects
				(font
					(size 1.27 1.27)
				)
				(justify left bottom)
				(hide yes)
			)
		)
		(pin "1"
		)
		(pin "2"
		)
		(instances
			(project "k410t-devboard"
				(path ""
					(reference "C76")
					(unit 1)
				)
			)
		)
	)
	(symbol
		(lib_id "antmicroFPGAChips:XC7K410T-2FFG900I")
		(at 177.8 87.63 0)
		(unit 4)
		(exclude_from_sim no)
		(in_bom yes)
		(on_board yes)
		(dnp no)
		(fields_autoplaced yes)
		(property "Reference" "U1"
			(at 204.47 77.47 0)
			(effects
				(font
					(size 1.27 1.27)
					(thickness 0.15)
				)
			)
		)
		(property "Value" "XC7K410T-2FFG900I"
			(at 204.47 80.01 0)
			(effects
				(font
					(size 1.27 1.27)
					(thickness 0.15)
				)
			)
		)
		(property "Footprint" "antmicro-footprints:BGA-900_31x31mm_Layout30x30_P1x1mm_FFG900"
			(at 177.8 60.96 0)
			(effects
				(font
					(size 1.27 1.27)
					(thickness 0.15)
				)
				(justify left bottom)
				(hide yes)
			)
		)
		(property "Datasheet" "https://eu.mouser.com/datasheet/2/903/ds180_7Series_Overview-1591537.pdf"
			(at 177.8 63.5 0)
			(effects
				(font
					(size 1.27 1.27)
					(thickness 0.15)
				)
				(justify left bottom)
				(hide yes)
			)
		)
		(property "Description" ""
			(at 177.8 87.63 0)
			(effects
				(font
					(size 1.27 1.27)
				)
			)
		)
		(property "Manufacturer" "AMD-Xilinx"
			(at 177.8 66.04 0)
			(effects
				(font
					(size 1.27 1.27)
					(thickness 0.15)
				)
				(justify left bottom)
				(hide yes)
			)
		)
		(property "MPN" "XC7K410T-2FFG900I"
			(at 177.8 68.58 0)
			(effects
				(font
					(size 1.27 1.27)
					(thickness 0.15)
				)
				(justify left bottom)
				(hide yes)
			)
		)
		(property "Author" "Antmicro"
			(at 177.8 71.12 0)
			(effects
				(font
					(size 1.27 1.27)
					(thickness 0.15)
				)
				(justify left bottom)
				(hide yes)
			)
		)
		(property "License" "Apache-2.0"
			(at 177.8 73.66 0)
			(effects
				(font
					(size 1.27 1.27)
					(thickness 0.15)
				)
				(justify left bottom)
				(hide yes)
			)
		)
		(pin "AA15"
		)
		(pin "AA16"
		)
		(pin "AA17"
		)
		(pin "AA18"
		)
		(pin "AB14"
		)
		(pin "AB15"
		)
		(pin "AB17"
		)
		(pin "AB18"
		)
		(pin "AB19"
		)
		(pin "AC14"
		)
		(pin "AC15"
		)
		(pin "AC16"
		)
		(pin "AC17"
		)
		(pin "AC19"
		)
		(pin "AD14"
		)
		(pin "AD16"
		)
		(pin "AD17"
		)
		(pin "AD18"
		)
		(pin "AD19"
		)
		(pin "AE14"
		)
		(pin "AE15"
		)
		(pin "AE16"
		)
		(pin "AE18"
		)
		(pin "AE19"
		)
		(pin "AF15"
		)
		(pin "AF16"
		)
		(pin "AF17"
		)
		(pin "AF18"
		)
		(pin "AG14"
		)
		(pin "AG15"
		)
		(pin "AG17"
		)
		(pin "AG18"
		)
		(pin "AG19"
		)
		(pin "AH15"
		)
		(pin "AH16"
		)
		(pin "AH17"
		)
		(pin "AH19"
		)
		(pin "AJ16"
		)
		(pin "AJ17"
		)
		(pin "AJ18"
		)
		(pin "AJ19"
		)
		(pin "AK15"
		)
		(pin "AK16"
		)
		(pin "AK18"
		)
		(pin "AK19"
		)
		(pin "Y14"
		)
		(pin "Y15"
		)
		(pin "Y16"
		)
		(pin "Y18"
		)
		(pin "Y19"
		)
		(pin "E28"
		)
		(pin "AA22"
		)
		(pin "AA23"
		)
		(pin "AB20"
		)
		(pin "AB22"
		)
		(pin "AB23"
		)
		(pin "AB24"
		)
		(pin "AC20"
		)
		(pin "AC21"
		)
		(pin "AC22"
		)
		(pin "AC24"
		)
		(pin "AC25"
		)
		(pin "AD21"
		)
		(pin "AD22"
		)
		(pin "AD23"
		)
		(pin "AD24"
		)
		(pin "AE20"
		)
		(pin "AE21"
		)
		(pin "AE23"
		)
		(pin "AE24"
		)
		(pin "AE25"
		)
		(pin "AF20"
		)
		(pin "AF21"
		)
		(pin "AF22"
		)
		(pin "AF23"
		)
		(pin "AF25"
		)
		(pin "AG20"
		)
		(pin "AG22"
		)
		(pin "AG23"
		)
		(pin "AG24"
		)
		(pin "AG25"
		)
		(pin "AH20"
		)
		(pin "AH21"
		)
		(pin "AH22"
		)
		(pin "AH24"
		)
		(pin "AH25"
		)
		(pin "AJ21"
		)
		(pin "AJ22"
		)
		(pin "AJ23"
		)
		(pin "AJ24"
		)
		(pin "AK20"
		)
		(pin "AK21"
		)
		(pin "AK23"
		)
		(pin "AK24"
		)
		(pin "AK25"
		)
		(pin "Y20"
		)
		(pin "Y21"
		)
		(pin "Y23"
		)
		(pin "Y24"
		)
		(pin "P24"
		)
		(pin "P26"
		)
		(pin "P27"
		)
		(pin "P28"
		)
		(pin "P29"
		)
		(pin "R19"
		)
		(pin "R20"
		)
		(pin "R21"
		)
		(pin "R23"
		)
		(pin "R24"
		)
		(pin "R25"
		)
		(pin "R26"
		)
		(pin "R28"
		)
		(pin "R29"
		)
		(pin "R30"
		)
		(pin "T20"
		)
		(pin "T21"
		)
		(pin "T22"
		)
		(pin "T23"
		)
		(pin "T25"
		)
		(pin "T26"
		)
		(pin "T27"
		)
		(pin "T28"
		)
		(pin "T30"
		)
		(pin "U19"
		)
		(pin "U20"
		)
		(pin "U22"
		)
		(pin "U23"
		)
		(pin "U24"
		)
		(pin "U25"
		)
		(pin "U27"
		)
		(pin "U28"
		)
		(pin "U29"
		)
		(pin "U30"
		)
		(pin "V19"
		)
		(pin "V20"
		)
		(pin "V21"
		)
		(pin "V22"
		)
		(pin "V24"
		)
		(pin "V25"
		)
		(pin "V26"
		)
		(pin "V27"
		)
		(pin "V29"
		)
		(pin "V30"
		)
		(pin "W19"
		)
		(pin "W21"
		)
		(pin "W22"
		)
		(pin "W23"
		)
		(pin "W24"
		)
		(pin "W26"
		)
		(pin "A23"
		)
		(pin "A25"
		)
		(pin "A26"
		)
		(pin "A27"
		)
		(pin "A28"
		)
		(pin "A30"
		)
		(pin "B23"
		)
		(pin "B24"
		)
		(pin "B25"
		)
		(pin "B27"
		)
		(pin "B28"
		)
		(pin "B29"
		)
		(pin "B30"
		)
		(pin "C24"
		)
		(pin "C25"
		)
		(pin "C26"
		)
		(pin "C27"
		)
		(pin "C29"
		)
		(pin "C30"
		)
		(pin "D23"
		)
		(pin "D24"
		)
		(pin "D26"
		)
		(pin "D27"
		)
		(pin "D28"
		)
		(pin "D29"
		)
		(pin "E23"
		)
		(pin "E24"
		)
		(pin "E25"
		)
		(pin "E26"
		)
		(pin "B2"
		)
		(pin "B5"
		)
		(pin "B6"
		)
		(pin "C3"
		)
		(pin "C4"
		)
		(pin "E29"
		)
		(pin "E30"
		)
		(pin "F23"
		)
		(pin "F25"
		)
		(pin "F26"
		)
		(pin "F27"
		)
		(pin "F28"
		)
		(pin "F30"
		)
		(pin "G23"
		)
		(pin "G24"
		)
		(pin "G25"
		)
		(pin "G27"
		)
		(pin "G28"
		)
		(pin "G29"
		)
		(pin "G30"
		)
		(pin "H24"
		)
		(pin "H25"
		)
		(pin "H26"
		)
		(pin "H27"
		)
		(pin "H30"
		)
		(pin "A11"
		)
		(pin "A12"
		)
		(pin "A13"
		)
		(pin "A15"
		)
		(pin "B12"
		)
		(pin "B13"
		)
		(pin "B14"
		)
		(pin "B15"
		)
		(pin "C11"
		)
		(pin "C12"
		)
		(pin "C14"
		)
		(pin "C15"
		)
		(pin "D11"
		)
		(pin "D12"
		)
		(pin "D13"
		)
		(pin "D14"
		)
		(pin "E11"
		)
		(pin "E13"
		)
		(pin "E14"
		)
		(pin "E15"
		)
		(pin "E16"
		)
		(pin "F11"
		)
		(pin "F12"
		)
		(pin "F13"
		)
		(pin "F15"
		)
		(pin "F16"
		)
		(pin "G12"
		)
		(pin "G13"
		)
		(pin "G14"
		)
		(pin "G15"
		)
		(pin "H11"
		)
		(pin "H12"
		)
		(pin "H14"
		)
		(pin "H15"
		)
		(pin "H16"
		)
		(pin "J11"
		)
		(pin "J12"
		)
		(pin "J13"
		)
		(pin "J14"
		)
		(pin "J16"
		)
		(pin "K11"
		)
		(pin "K13"
		)
		(pin "K14"
		)
		(pin "K15"
		)
		(pin "K16"
		)
		(pin "L11"
		)
		(pin "L12"
		)
		(pin "L13"
		)
		(pin "L15"
		)
		(pin "L16"
		)
		(pin "AA10"
		)
		(pin "AA11"
		)
		(pin "AA12"
		)
		(pin "AA13"
		)
		(pin "AA8"
		)
		(pin "AB10"
		)
		(pin "AB12"
		)
		(pin "AB13"
		)
		(pin "AB8"
		)
		(pin "AB9"
		)
		(pin "AC10"
		)
		(pin "AC11"
		)
		(pin "AC12"
		)
		(pin "AC9"
		)
		(pin "AD11"
		)
		(pin "AD12"
		)
		(pin "AD13"
		)
		(pin "AD8"
		)
		(pin "AD9"
		)
		(pin "AE10"
		)
		(pin "AE11"
		)
		(pin "AE13"
		)
		(pin "AE8"
		)
		(pin "AE9"
		)
		(pin "AF10"
		)
		(pin "AF11"
		)
		(pin "AF12"
		)
		(pin "AF13"
		)
		(pin "AG10"
		)
		(pin "AG12"
		)
		(pin "AG13"
		)
		(pin "AG9"
		)
		(pin "AH10"
		)
		(pin "AH11"
		)
		(pin "AH12"
		)
		(pin "AH14"
		)
		(pin "AH9"
		)
		(pin "AJ11"
		)
		(pin "AJ12"
		)
		(pin "AJ13"
		)
		(pin "AJ14"
		)
		(pin "AJ9"
		)
		(pin "AK10"
		)
		(pin "AK11"
		)
		(pin "AK13"
		)
		(pin "AK14"
		)
		(pin "AK9"
		)
		(pin "Y10"
		)
		(pin "Y11"
		)
		(pin "Y13"
		)
		(pin "A3"
		)
		(pin "A4"
		)
		(pin "A7"
		)
		(pin "A8"
		)
		(pin "AA3"
		)
		(pin "AA4"
		)
		(pin "B1"
		)
		(pin "G16"
		)
		(pin "G2"
		)
		(pin "G26"
		)
		(pin "G6"
		)
		(pin "G9"
		)
		(pin "H13"
		)
		(pin "H23"
		)
		(pin "H4"
		)
		(pin "H8"
		)
		(pin "H9"
		)
		(pin "J1"
		)
		(pin "J10"
		)
		(pin "C7"
		)
		(pin "C8"
		)
		(pin "D1"
		)
		(pin "D2"
		)
		(pin "D5"
		)
		(pin "D6"
		)
		(pin "E3"
		)
		(pin "E4"
		)
		(pin "E7"
		)
		(pin "E8"
		)
		(pin "F1"
		)
		(pin "F2"
		)
		(pin "F5"
		)
		(pin "F6"
		)
		(pin "G3"
		)
		(pin "G4"
		)
		(pin "G7"
		)
		(pin "G8"
		)
		(pin "H1"
		)
		(pin "H2"
		)
		(pin "H5"
		)
		(pin "H6"
		)
		(pin "J3"
		)
		(pin "J4"
		)
		(pin "J7"
		)
		(pin "J8"
		)
		(pin "K1"
		)
		(pin "K2"
		)
		(pin "K5"
		)
		(pin "K6"
		)
		(pin "L3"
		)
		(pin "L4"
		)
		(pin "L7"
		)
		(pin "L8"
		)
		(pin "M1"
		)
		(pin "M2"
		)
		(pin "M5"
		)
		(pin "M6"
		)
		(pin "N3"
		)
		(pin "N4"
		)
		(pin "N7"
		)
		(pin "N8"
		)
		(pin "P1"
		)
		(pin "P2"
		)
		(pin "P5"
		)
		(pin "P6"
		)
		(pin "R3"
		)
		(pin "R4"
		)
		(pin "R7"
		)
		(pin "R8"
		)
		(pin "T1"
		)
		(pin "T2"
		)
		(pin "T5"
		)
		(pin "T6"
		)
		(pin "U3"
		)
		(pin "U4"
		)
		(pin "U7"
		)
		(pin "U8"
		)
		(pin "V1"
		)
		(pin "V2"
		)
		(pin "V5"
		)
		(pin "V6"
		)
		(pin "W3"
		)
		(pin "W4"
		)
		(pin "Y1"
		)
		(pin "Y2"
		)
		(pin "Y5"
		)
		(pin "Y6"
		)
		(pin "B3"
		)
		(pin "B7"
		)
		(pin "C5"
		)
		(pin "D3"
		)
		(pin "D7"
		)
		(pin "E5"
		)
		(pin "F3"
		)
		(pin "F7"
		)
		(pin "G5"
		)
		(pin "H3"
		)
		(pin "H7"
		)
		(pin "J5"
		)
		(pin "K3"
		)
		(pin "K7"
		)
		(pin "L5"
		)
		(pin "M3"
		)
		(pin "M7"
		)
		(pin "N5"
		)
		(pin "P3"
		)
		(pin "P7"
		)
		(pin "R5"
		)
		(pin "T3"
		)
		(pin "T7"
		)
		(pin "U5"
		)
		(pin "V3"
		)
		(pin "V7"
		)
		(pin "W5"
		)
		(pin "W7"
		)
		(pin "W8"
		)
		(pin "A10"
		)
		(pin "AB1"
		)
		(pin "AB2"
		)
		(pin "AB5"
		)
		(pin "B10"
		)
		(pin "E10"
		)
		(pin "F10"
		)
		(pin "G10"
		)
		(pin "H10"
		)
		(pin "K10"
		)
		(pin "L10"
		)
		(pin "M10"
		)
		(pin "R14"
		)
		(pin "R15"
		)
		(pin "T14"
		)
		(pin "T15"
		)
		(pin "U14"
		)
		(pin "U15"
		)
		(pin "A19"
		)
		(pin "A29"
		)
		(pin "AA19"
		)
		(pin "AA29"
		)
		(pin "AA9"
		)
		(pin "AB16"
		)
		(pin "AB26"
		)
		(pin "AB6"
		)
		(pin "AC13"
		)
		(pin "AC23"
		)
		(pin "AC3"
		)
		(pin "AD10"
		)
		(pin "AD20"
		)
		(pin "AD30"
		)
		(pin "AE17"
		)
		(pin "AE27"
		)
		(pin "AE7"
		)
		(pin "AF14"
		)
		(pin "AF24"
		)
		(pin "AF4"
		)
		(pin "AG1"
		)
		(pin "AG11"
		)
		(pin "AG21"
		)
		(pin "AH18"
		)
		(pin "AH28"
		)
		(pin "AH8"
		)
		(pin "AJ15"
		)
		(pin "AJ25"
		)
		(pin "AJ5"
		)
		(pin "AK12"
		)
		(pin "AK2"
		)
		(pin "AK22"
		)
		(pin "B16"
		)
		(pin "B26"
		)
		(pin "C13"
		)
		(pin "C23"
		)
		(pin "D10"
		)
		(pin "D20"
		)
		(pin "D30"
		)
		(pin "E17"
		)
		(pin "E27"
		)
		(pin "F14"
		)
		(pin "F24"
		)
		(pin "G11"
		)
		(pin "G21"
		)
		(pin "H18"
		)
		(pin "H28"
		)
		(pin "J15"
		)
		(pin "J25"
		)
		(pin "K12"
		)
		(pin "K22"
		)
		(pin "L19"
		)
		(pin "L29"
		)
		(pin "M26"
		)
		(pin "N23"
		)
		(pin "P20"
		)
		(pin "P30"
		)
		(pin "R27"
		)
		(pin "T24"
		)
		(pin "T9"
		)
		(pin "U21"
		)
		(pin "V28"
		)
		(pin "W25"
		)
		(pin "Y12"
		)
		(pin "Y22"
		)
		(pin "A1"
		)
		(pin "A14"
		)
		(pin "A2"
		)
		(pin "A24"
		)
		(pin "A5"
		)
		(pin "A6"
		)
		(pin "A9"
		)
		(pin "AA1"
		)
		(pin "AA14"
		)
		(pin "AA2"
		)
		(pin "AA24"
		)
		(pin "AA5"
		)
		(pin "AA6"
		)
		(pin "AA7"
		)
		(pin "AB11"
		)
		(pin "AB21"
		)
		(pin "AB3"
		)
		(pin "AB4"
		)
		(pin "AC18"
		)
		(pin "AC28"
		)
		(pin "AC8"
		)
		(pin "AD15"
		)
		(pin "AD25"
		)
		(pin "AD5"
		)
		(pin "AE12"
		)
		(pin "AE2"
		)
		(pin "AE22"
		)
		(pin "AF19"
		)
		(pin "AF29"
		)
		(pin "AF9"
		)
		(pin "AG16"
		)
		(pin "AG26"
		)
		(pin "AG6"
		)
		(pin "AH13"
		)
		(pin "AH23"
		)
		(pin "AH3"
		)
		(pin "AJ10"
		)
		(pin "AJ20"
		)
		(pin "AJ30"
		)
		(pin "AK17"
		)
		(pin "AK27"
		)
		(pin "AK7"
		)
		(pin "B11"
		)
		(pin "B21"
		)
		(pin "B4"
		)
		(pin "B8"
		)
		(pin "B9"
		)
		(pin "C1"
		)
		(pin "C10"
		)
		(pin "C18"
		)
		(pin "C2"
		)
		(pin "C28"
		)
		(pin "C6"
		)
		(pin "C9"
		)
		(pin "D15"
		)
		(pin "D25"
		)
		(pin "D4"
		)
		(pin "D8"
		)
		(pin "D9"
		)
		(pin "E1"
		)
		(pin "E12"
		)
		(pin "E2"
		)
		(pin "E22"
		)
		(pin "E6"
		)
		(pin "E9"
		)
		(pin "F19"
		)
		(pin "F29"
		)
		(pin "F4"
		)
		(pin "F8"
		)
		(pin "F9"
		)
		(pin "G1"
		)
		(pin "J2"
		)
		(pin "J20"
		)
		(pin "J30"
		)
		(pin "J6"
		)
		(pin "J9"
		)
		(pin "K17"
		)
		(pin "K27"
		)
		(pin "K4"
		)
		(pin "K8"
		)
		(pin "K9"
		)
		(pin "L1"
		)
		(pin "L14"
		)
		(pin "L2"
		)
		(pin "L24"
		)
		(pin "L6"
		)
		(pin "L9"
		)
		(pin "M11"
		)
		(pin "M12"
		)
		(pin "M13"
		)
		(pin "M14"
		)
		(pin "M15"
		)
		(pin "M16"
		)
		(pin "M17"
		)
		(pin "M18"
		)
		(pin "M21"
		)
		(pin "M4"
		)
		(pin "M8"
		)
		(pin "M9"
		)
		(pin "N1"
		)
		(pin "N10"
		)
		(pin "N11"
		)
		(pin "N12"
		)
		(pin "N13"
		)
		(pin "N14"
		)
		(pin "N15"
		)
		(pin "N16"
		)
		(pin "N17"
		)
		(pin "N18"
		)
		(pin "N2"
		)
		(pin "N28"
		)
		(pin "N6"
		)
		(pin "N9"
		)
		(pin "P10"
		)
		(pin "P11"
		)
		(pin "P12"
		)
		(pin "P13"
		)
		(pin "P14"
		)
		(pin "P15"
		)
		(pin "P16"
		)
		(pin "P17"
		)
		(pin "P18"
		)
		(pin "P25"
		)
		(pin "P4"
		)
		(pin "P8"
		)
		(pin "P9"
		)
		(pin "R1"
		)
		(pin "R10"
		)
		(pin "R11"
		)
		(pin "R12"
		)
		(pin "R13"
		)
		(pin "R16"
		)
		(pin "R17"
		)
		(pin "R18"
		)
		(pin "R2"
		)
		(pin "R22"
		)
		(pin "R6"
		)
		(pin "R9"
		)
		(pin "T10"
		)
		(pin "T11"
		)
		(pin "T12"
		)
		(pin "T13"
		)
		(pin "T16"
		)
		(pin "T17"
		)
		(pin "T18"
		)
		(pin "T19"
		)
		(pin "T29"
		)
		(pin "T4"
		)
		(pin "T8"
		)
		(pin "U1"
		)
		(pin "U10"
		)
		(pin "U11"
		)
		(pin "U12"
		)
		(pin "U13"
		)
		(pin "U16"
		)
		(pin "U17"
		)
		(pin "U18"
		)
		(pin "U2"
		)
		(pin "U26"
		)
		(pin "U6"
		)
		(pin "U9"
		)
		(pin "V10"
		)
		(pin "V11"
		)
		(pin "V12"
		)
		(pin "V13"
		)
		(pin "V14"
		)
		(pin "V15"
		)
		(pin "V16"
		)
		(pin "V17"
		)
		(pin "V18"
		)
		(pin "V23"
		)
		(pin "V4"
		)
		(pin "V8"
		)
		(pin "V9"
		)
		(pin "W1"
		)
		(pin "W10"
		)
		(pin "W11"
		)
		(pin "W12"
		)
		(pin "W13"
		)
		(pin "W14"
		)
		(pin "W15"
		)
		(pin "W16"
		)
		(pin "W17"
		)
		(pin "W18"
		)
		(pin "W2"
		)
		(pin "W20"
		)
		(pin "W30"
		)
		(pin "W6"
		)
		(pin "W9"
		)
		(pin "Y17"
		)
		(pin "Y27"
		)
		(pin "Y3"
		)
		(pin "Y4"
		)
		(pin "Y7"
		)
		(pin "Y8"
		)
		(pin "Y9"
		)
		(pin "AA25"
		)
		(pin "AA26"
		)
		(pin "AA27"
		)
		(pin "AA28"
		)
		(pin "AA30"
		)
		(pin "AB25"
		)
		(pin "AB27"
		)
		(pin "AB28"
		)
		(pin "AB29"
		)
		(pin "AB30"
		)
		(pin "AC26"
		)
		(pin "AC27"
		)
		(pin "AC29"
		)
		(pin "AC30"
		)
		(pin "AD26"
		)
		(pin "AD27"
		)
		(pin "AD28"
		)
		(pin "AD29"
		)
		(pin "AE26"
		)
		(pin "AE28"
		)
		(pin "AE29"
		)
		(pin "AE30"
		)
		(pin "AF26"
		)
		(pin "AF27"
		)
		(pin "AF28"
		)
		(pin "AF30"
		)
		(pin "AG27"
		)
		(pin "AG28"
		)
		(pin "AG29"
		)
		(pin "AG30"
		)
		(pin "AH26"
		)
		(pin "AH27"
		)
		(pin "AH29"
		)
		(pin "AH30"
		)
		(pin "AJ26"
		)
		(pin "AJ27"
		)
		(pin "AJ28"
		)
		(pin "AJ29"
		)
		(pin "AK26"
		)
		(pin "AK28"
		)
		(pin "AK29"
		)
		(pin "AK30"
		)
		(pin "W27"
		)
		(pin "W28"
		)
		(pin "W29"
		)
		(pin "Y25"
		)
		(pin "Y26"
		)
		(pin "Y28"
		)
		(pin "Y29"
		)
		(pin "Y30"
		)
		(pin "H29"
		)
		(pin "J21"
		)
		(pin "J22"
		)
		(pin "J23"
		)
		(pin "J24"
		)
		(pin "J26"
		)
		(pin "J27"
		)
		(pin "J28"
		)
		(pin "J29"
		)
		(pin "K21"
		)
		(pin "K23"
		)
		(pin "K24"
		)
		(pin "K25"
		)
		(pin "K26"
		)
		(pin "K28"
		)
		(pin "K29"
		)
		(pin "K30"
		)
		(pin "L20"
		)
		(pin "L21"
		)
		(pin "L22"
		)
		(pin "L23"
		)
		(pin "L25"
		)
		(pin "L26"
		)
		(pin "L27"
		)
		(pin "L28"
		)
		(pin "L30"
		)
		(pin "M19"
		)
		(pin "M20"
		)
		(pin "M22"
		)
		(pin "M23"
		)
		(pin "M24"
		)
		(pin "M25"
		)
		(pin "M27"
		)
		(pin "M28"
		)
		(pin "M29"
		)
		(pin "M30"
		)
		(pin "N19"
		)
		(pin "N20"
		)
		(pin "N21"
		)
		(pin "N22"
		)
		(pin "N24"
		)
		(pin "N25"
		)
		(pin "N26"
		)
		(pin "N27"
		)
		(pin "N29"
		)
		(pin "N30"
		)
		(pin "P19"
		)
		(pin "P21"
		)
		(pin "P22"
		)
		(pin "P23"
		)
		(pin "A16"
		)
		(pin "A17"
		)
		(pin "A18"
		)
		(pin "A20"
		)
		(pin "A21"
		)
		(pin "A22"
		)
		(pin "B17"
		)
		(pin "B18"
		)
		(pin "B19"
		)
		(pin "B20"
		)
		(pin "B22"
		)
		(pin "C16"
		)
		(pin "C17"
		)
		(pin "C19"
		)
		(pin "C20"
		)
		(pin "C21"
		)
		(pin "C22"
		)
		(pin "D16"
		)
		(pin "D17"
		)
		(pin "D18"
		)
		(pin "D19"
		)
		(pin "D21"
		)
		(pin "D22"
		)
		(pin "E18"
		)
		(pin "E19"
		)
		(pin "E20"
		)
		(pin "E21"
		)
		(pin "F17"
		)
		(pin "F18"
		)
		(pin "F20"
		)
		(pin "F21"
		)
		(pin "F22"
		)
		(pin "G17"
		)
		(pin "G18"
		)
		(pin "G19"
		)
		(pin "G20"
		)
		(pin "G22"
		)
		(pin "H17"
		)
		(pin "H19"
		)
		(pin "H20"
		)
		(pin "H21"
		)
		(pin "H22"
		)
		(pin "J17"
		)
		(pin "J18"
		)
		(pin "J19"
		)
		(pin "K18"
		)
		(pin "K19"
		)
		(pin "K20"
		)
		(pin "L17"
		)
		(pin "L18"
		)
		(pin "AB7"
		)
		(pin "AC1"
		)
		(pin "AC2"
		)
		(pin "AC4"
		)
		(pin "AC5"
		)
		(pin "AC6"
		)
		(pin "AC7"
		)
		(pin "AD1"
		)
		(pin "AD2"
		)
		(pin "AD3"
		)
		(pin "AD4"
		)
		(pin "AD6"
		)
		(pin "AD7"
		)
		(pin "AE1"
		)
		(pin "AE3"
		)
		(pin "AE4"
		)
		(pin "AE5"
		)
		(pin "AE6"
		)
		(pin "AF1"
		)
		(pin "AF2"
		)
		(pin "AF3"
		)
		(pin "AF5"
		)
		(pin "AF6"
		)
		(pin "AF7"
		)
		(pin "AF8"
		)
		(pin "AG2"
		)
		(pin "AG3"
		)
		(pin "AG4"
		)
		(pin "AG5"
		)
		(pin "AG7"
		)
		(pin "AG8"
		)
		(pin "AH1"
		)
		(pin "AH2"
		)
		(pin "AH4"
		)
		(pin "AH5"
		)
		(pin "AH6"
		)
		(pin "AH7"
		)
		(pin "AJ1"
		)
		(pin "AJ2"
		)
		(pin "AJ3"
		)
		(pin "AJ4"
		)
		(pin "AJ6"
		)
		(pin "AJ7"
		)
		(pin "AJ8"
		)
		(pin "AK1"
		)
		(pin "AK3"
		)
		(pin "AK4"
		)
		(pin "AK5"
		)
		(pin "AK6"
		)
		(pin "AK8"
		)
		(pin "AA20"
		)
		(pin "AA21"
		)
		(instances
			(project "k410t-devboard"
				(path ""
					(reference "U1")
					(unit 4)
				)
			)
		)
	)
	(symbol
		(lib_id "antmicroCapacitors0402:C_100n_0402")
		(at 252.73 67.31 90)
		(unit 1)
		(exclude_from_sim no)
		(in_bom yes)
		(on_board yes)
		(dnp no)
		(property "Reference" "C83"
			(at 253.365 62.865 90)
			(effects
				(font
					(size 1.27 1.27)
				)
				(justify right)
			)
		)
		(property "Value" "C_100n_0402"
			(at 262.89 46.99 0)
			(effects
				(font
					(size 1.27 1.27)
					(thickness 0.15)
				)
				(justify left bottom)
				(hide yes)
			)
		)
		(property "Footprint" "antmicro-footprints:C_0402_1005Metric"
			(at 265.43 46.99 0)
			(effects
				(font
					(size 1.27 1.27)
					(thickness 0.15)
				)
				(justify left bottom)
				(hide yes)
			)
		)
		(property "Datasheet" "https://www.murata.com/products/productdetail?partno=GRM155R61H104KE14%23"
			(at 267.97 46.99 0)
			(effects
				(font
					(size 1.27 1.27)
					(thickness 0.15)
				)
				(justify left bottom)
				(hide yes)
			)
		)
		(property "Description" ""
			(at 252.73 67.31 0)
			(effects
				(font
					(size 1.27 1.27)
				)
			)
		)
		(property "Manufacturer" "Murata"
			(at 273.05 46.99 0)
			(effects
				(font
					(size 1.27 1.27)
					(thickness 0.15)
				)
				(justify left bottom)
				(hide yes)
			)
		)
		(property "MPN" "GRM155R61H104KE14D"
			(at 270.51 46.99 0)
			(effects
				(font
					(size 1.27 1.27)
					(thickness 0.15)
				)
				(justify left bottom)
				(hide yes)
			)
		)
		(property "Val" "100n"
			(at 253.365 66.675 90)
			(effects
				(font
					(size 1.27 1.27)
					(thickness 0.15)
				)
				(justify right)
			)
		)
		(property "License" "Apache-2.0"
			(at 275.59 46.99 0)
			(effects
				(font
					(size 1.27 1.27)
					(thickness 0.15)
				)
				(justify left bottom)
				(hide yes)
			)
		)
		(property "Author" "Antmicro"
			(at 278.13 46.99 0)
			(effects
				(font
					(size 1.27 1.27)
					(thickness 0.15)
				)
				(justify left bottom)
				(hide yes)
			)
		)
		(property "Voltage" "50V"
			(at 280.67 46.99 0)
			(effects
				(font
					(size 1.27 1.27)
				)
				(justify left bottom)
				(hide yes)
			)
		)
		(property "Dielectric" "X5R"
			(at 283.21 46.99 0)
			(effects
				(font
					(size 1.27 1.27)
				)
				(justify left bottom)
				(hide yes)
			)
		)
		(pin "1"
		)
		(pin "2"
		)
		(instances
			(project "k410t-devboard"
				(path ""
					(reference "C83")
					(unit 1)
				)
			)
		)
	)
	(symbol
		(lib_id "antmicropower:+1V8")
		(at 289.56 57.15 0)
		(unit 1)
		(exclude_from_sim no)
		(in_bom yes)
		(on_board yes)
		(dnp no)
		(fields_autoplaced yes)
		(property "Reference" "#PWR028"
			(at 289.56 60.96 0)
			(effects
				(font
					(size 1.27 1.27)
				)
				(hide yes)
			)
		)
		(property "Value" "+1V8"
			(at 289.56 53.594 0)
			(effects
				(font
					(size 1.27 1.27)
				)
			)
		)
		(property "Footprint" ""
			(at 304.8 64.77 0)
			(effects
				(font
					(size 1.27 1.27)
					(thickness 0.15)
				)
				(justify left bottom)
				(hide yes)
			)
		)
		(property "Datasheet" ""
			(at 304.8 67.31 0)
			(effects
				(font
					(size 1.27 1.27)
					(thickness 0.15)
				)
				(justify left bottom)
				(hide yes)
			)
		)
		(property "Description" ""
			(at 289.56 57.15 0)
			(effects
				(font
					(size 1.27 1.27)
				)
			)
		)
		(property "Author" "Antmicro"
			(at 304.8 64.77 0)
			(effects
				(font
					(size 1.27 1.27)
					(thickness 0.15)
				)
				(justify left bottom)
				(hide yes)
			)
		)
		(property "License" "Apache-2.0"
			(at 304.8 67.31 0)
			(effects
				(font
					(size 1.27 1.27)
					(thickness 0.15)
				)
				(justify left bottom)
				(hide yes)
			)
		)
		(pin "1"
		)
		(instances
			(project "k410t-devboard"
				(path ""
					(reference "#PWR028")
					(unit 1)
				)
			)
		)
	)
	(symbol
		(lib_id "antmicropower:GND")
		(at 127 71.12 0)
		(unit 1)
		(exclude_from_sim no)
		(in_bom yes)
		(on_board yes)
		(dnp no)
		(property "Reference" "#PWR024"
			(at 127 77.47 0)
			(effects
				(font
					(size 1.27 1.27)
				)
				(hide yes)
			)
		)
		(property "Value" "GND"
			(at 127 74.93 0)
			(effects
				(font
					(size 1.27 1.27)
				)
			)
		)
		(property "Footprint" ""
			(at 135.89 78.74 0)
			(effects
				(font
					(size 1.27 1.27)
					(thickness 0.15)
				)
				(justify left bottom)
				(hide yes)
			)
		)
		(property "Datasheet" ""
			(at 135.89 83.82 0)
			(effects
				(font
					(size 1.27 1.27)
					(thickness 0.15)
				)
				(justify left bottom)
				(hide yes)
			)
		)
		(property "Description" ""
			(at 127 71.12 0)
			(effects
				(font
					(size 1.27 1.27)
				)
			)
		)
		(property "Author" "Antmicro"
			(at 135.89 78.74 0)
			(effects
				(font
					(size 1.27 1.27)
					(thickness 0.15)
				)
				(justify left bottom)
				(hide yes)
			)
		)
		(property "License" "Apache-2.0"
			(at 135.89 81.28 0)
			(effects
				(font
					(size 1.27 1.27)
					(thickness 0.15)
				)
				(justify left bottom)
				(hide yes)
			)
		)
		(pin "1"
		)
		(instances
			(project "k410t-devboard"
				(path ""
					(reference "#PWR024")
					(unit 1)
				)
			)
		)
	)
	(symbol
		(lib_id "antmicroCapacitors0402:C_100n_0402")
		(at 157.48 67.31 270)
		(mirror x)
		(unit 1)
		(exclude_from_sim no)
		(in_bom yes)
		(on_board yes)
		(dnp no)
		(property "Reference" "C82"
			(at 156.845 62.865 90)
			(effects
				(font
					(size 1.27 1.27)
				)
				(justify right)
			)
		)
		(property "Value" "C_100n_0402"
			(at 147.32 46.99 0)
			(effects
				(font
					(size 1.27 1.27)
					(thickness 0.15)
				)
				(justify left bottom)
				(hide yes)
			)
		)
		(property "Footprint" "antmicro-footprints:C_0402_1005Metric"
			(at 144.78 46.99 0)
			(effects
				(font
					(size 1.27 1.27)
					(thickness 0.15)
				)
				(justify left bottom)
				(hide yes)
			)
		)
		(property "Datasheet" "https://www.murata.com/products/productdetail?partno=GRM155R61H104KE14%23"
			(at 142.24 46.99 0)
			(effects
				(font
					(size 1.27 1.27)
					(thickness 0.15)
				)
				(justify left bottom)
				(hide yes)
			)
		)
		(property "Description" ""
			(at 157.48 67.31 0)
			(effects
				(font
					(size 1.27 1.27)
				)
			)
		)
		(property "Manufacturer" "Murata"
			(at 137.16 46.99 0)
			(effects
				(font
					(size 1.27 1.27)
					(thickness 0.15)
				)
				(justify left bottom)
				(hide yes)
			)
		)
		(property "MPN" "GRM155R61H104KE14D"
			(at 139.7 46.99 0)
			(effects
				(font
					(size 1.27 1.27)
					(thickness 0.15)
				)
				(justify left bottom)
				(hide yes)
			)
		)
		(property "Val" "100n"
			(at 156.845 66.675 90)
			(effects
				(font
					(size 1.27 1.27)
					(thickness 0.15)
				)
				(justify right)
			)
		)
		(property "License" "Apache-2.0"
			(at 134.62 46.99 0)
			(effects
				(font
					(size 1.27 1.27)
					(thickness 0.15)
				)
				(justify left bottom)
				(hide yes)
			)
		)
		(property "Author" "Antmicro"
			(at 132.08 46.99 0)
			(effects
				(font
					(size 1.27 1.27)
					(thickness 0.15)
				)
				(justify left bottom)
				(hide yes)
			)
		)
		(property "Voltage" "50V"
			(at 129.54 46.99 0)
			(effects
				(font
					(size 1.27 1.27)
				)
				(justify left bottom)
				(hide yes)
			)
		)
		(property "Dielectric" "X5R"
			(at 127 46.99 0)
			(effects
				(font
					(size 1.27 1.27)
				)
				(justify left bottom)
				(hide yes)
			)
		)
		(pin "1"
		)
		(pin "2"
		)
		(instances
			(project "k410t-devboard"
				(path ""
					(reference "C82")
					(unit 1)
				)
			)
		)
	)
	(symbol
		(lib_id "antmicroCapacitors0402:C_100n_0402")
		(at 134.62 67.31 270)
		(mirror x)
		(unit 1)
		(exclude_from_sim no)
		(in_bom yes)
		(on_board yes)
		(dnp no)
		(property "Reference" "C99"
			(at 133.985 62.865 90)
			(effects
				(font
					(size 1.27 1.27)
				)
				(justify right)
			)
		)
		(property "Value" "C_100n_0402"
			(at 124.46 46.99 0)
			(effects
				(font
					(size 1.27 1.27)
					(thickness 0.15)
				)
				(justify left bottom)
				(hide yes)
			)
		)
		(property "Footprint" "antmicro-footprints:C_0402_1005Metric"
			(at 121.92 46.99 0)
			(effects
				(font
					(size 1.27 1.27)
					(thickness 0.15)
				)
				(justify left bottom)
				(hide yes)
			)
		)
		(property "Datasheet" "https://www.murata.com/products/productdetail?partno=GRM155R61H104KE14%23"
			(at 119.38 46.99 0)
			(effects
				(font
					(size 1.27 1.27)
					(thickness 0.15)
				)
				(justify left bottom)
				(hide yes)
			)
		)
		(property "Description" ""
			(at 134.62 67.31 0)
			(effects
				(font
					(size 1.27 1.27)
				)
			)
		)
		(property "Manufacturer" "Murata"
			(at 114.3 46.99 0)
			(effects
				(font
					(size 1.27 1.27)
					(thickness 0.15)
				)
				(justify left bottom)
				(hide yes)
			)
		)
		(property "MPN" "GRM155R61H104KE14D"
			(at 116.84 46.99 0)
			(effects
				(font
					(size 1.27 1.27)
					(thickness 0.15)
				)
				(justify left bottom)
				(hide yes)
			)
		)
		(property "Val" "100n"
			(at 133.985 66.675 90)
			(effects
				(font
					(size 1.27 1.27)
					(thickness 0.15)
				)
				(justify right)
			)
		)
		(property "License" "Apache-2.0"
			(at 111.76 46.99 0)
			(effects
				(font
					(size 1.27 1.27)
					(thickness 0.15)
				)
				(justify left bottom)
				(hide yes)
			)
		)
		(property "Author" "Antmicro"
			(at 109.22 46.99 0)
			(effects
				(font
					(size 1.27 1.27)
					(thickness 0.15)
				)
				(justify left bottom)
				(hide yes)
			)
		)
		(property "Voltage" "50V"
			(at 106.68 46.99 0)
			(effects
				(font
					(size 1.27 1.27)
				)
				(justify left bottom)
				(hide yes)
			)
		)
		(property "Dielectric" "X5R"
			(at 104.14 46.99 0)
			(effects
				(font
					(size 1.27 1.27)
				)
				(justify left bottom)
				(hide yes)
			)
		)
		(pin "1"
		)
		(pin "2"
		)
		(instances
			(project "k410t-devboard"
				(path ""
					(reference "C99")
					(unit 1)
				)
			)
		)
	)
	(symbol
		(lib_id "antmicroCapacitors0402:C_100n_0402")
		(at 275.59 67.31 90)
		(unit 1)
		(exclude_from_sim no)
		(in_bom yes)
		(on_board yes)
		(dnp no)
		(property "Reference" "C100"
			(at 276.225 62.865 90)
			(effects
				(font
					(size 1.27 1.27)
				)
				(justify right)
			)
		)
		(property "Value" "C_100n_0402"
			(at 285.75 46.99 0)
			(effects
				(font
					(size 1.27 1.27)
					(thickness 0.15)
				)
				(justify left bottom)
				(hide yes)
			)
		)
		(property "Footprint" "antmicro-footprints:C_0402_1005Metric"
			(at 288.29 46.99 0)
			(effects
				(font
					(size 1.27 1.27)
					(thickness 0.15)
				)
				(justify left bottom)
				(hide yes)
			)
		)
		(property "Datasheet" "https://www.murata.com/products/productdetail?partno=GRM155R61H104KE14%23"
			(at 290.83 46.99 0)
			(effects
				(font
					(size 1.27 1.27)
					(thickness 0.15)
				)
				(justify left bottom)
				(hide yes)
			)
		)
		(property "Description" ""
			(at 275.59 67.31 0)
			(effects
				(font
					(size 1.27 1.27)
				)
			)
		)
		(property "Manufacturer" "Murata"
			(at 295.91 46.99 0)
			(effects
				(font
					(size 1.27 1.27)
					(thickness 0.15)
				)
				(justify left bottom)
				(hide yes)
			)
		)
		(property "MPN" "GRM155R61H104KE14D"
			(at 293.37 46.99 0)
			(effects
				(font
					(size 1.27 1.27)
					(thickness 0.15)
				)
				(justify left bottom)
				(hide yes)
			)
		)
		(property "Val" "100n"
			(at 276.225 66.675 90)
			(effects
				(font
					(size 1.27 1.27)
					(thickness 0.15)
				)
				(justify right)
			)
		)
		(property "License" "Apache-2.0"
			(at 298.45 46.99 0)
			(effects
				(font
					(size 1.27 1.27)
					(thickness 0.15)
				)
				(justify left bottom)
				(hide yes)
			)
		)
		(property "Author" "Antmicro"
			(at 300.99 46.99 0)
			(effects
				(font
					(size 1.27 1.27)
					(thickness 0.15)
				)
				(justify left bottom)
				(hide yes)
			)
		)
		(property "Voltage" "50V"
			(at 303.53 46.99 0)
			(effects
				(font
					(size 1.27 1.27)
				)
				(justify left bottom)
				(hide yes)
			)
		)
		(property "Dielectric" "X5R"
			(at 306.07 46.99 0)
			(effects
				(font
					(size 1.27 1.27)
				)
				(justify left bottom)
				(hide yes)
			)
		)
		(pin "1"
		)
		(pin "2"
		)
		(instances
			(project "k410t-devboard"
				(path ""
					(reference "C100")
					(unit 1)
				)
			)
		)
	)
	(symbol
		(lib_id "antmicropower:+3.3V")
		(at 121.92 57.15 0)
		(mirror y)
		(unit 1)
		(exclude_from_sim no)
		(in_bom yes)
		(on_board yes)
		(dnp no)
		(fields_autoplaced yes)
		(property "Reference" "#PWR027"
			(at 121.92 60.96 0)
			(effects
				(font
					(size 1.27 1.27)
				)
				(hide yes)
			)
		)
		(property "Value" "+3V3"
			(at 121.92 53.594 0)
			(effects
				(font
					(size 1.27 1.27)
				)
			)
		)
		(property "Footprint" ""
			(at 121.92 57.15 0)
			(effects
				(font
					(size 1.27 1.27)
				)
				(hide yes)
			)
		)
		(property "Datasheet" ""
			(at 121.92 57.15 0)
			(effects
				(font
					(size 1.27 1.27)
				)
				(hide yes)
			)
		)
		(property "Description" ""
			(at 121.92 57.15 0)
			(effects
				(font
					(size 1.27 1.27)
				)
			)
		)
		(pin "1"
		)
		(instances
			(project "k410t-devboard"
				(path ""
					(reference "#PWR027")
					(unit 1)
				)
			)
		)
	)
	(symbol
		(lib_id "antmicroCapacitors0603:C_47u_0603")
		(at 283.21 62.23 90)
		(mirror x)
		(unit 1)
		(exclude_from_sim no)
		(in_bom yes)
		(on_board yes)
		(dnp no)
		(property "Reference" "C107"
			(at 283.845 62.8777 90)
			(effects
				(font
					(size 1.27 1.27)
				)
				(justify right)
			)
		)
		(property "Value" "C_47u_0603"
			(at 293.37 82.55 0)
			(effects
				(font
					(size 1.27 1.27)
					(thickness 0.15)
				)
				(justify left bottom)
				(hide yes)
			)
		)
		(property "Footprint" "antmicro-footprints:C_0603_1608Metric"
			(at 295.91 82.55 0)
			(effects
				(font
					(size 1.27 1.27)
					(thickness 0.15)
				)
				(justify left bottom)
				(hide yes)
			)
		)
		(property "Datasheet" "https://www.murata.com/products/productdetail?partno=GRM188R60J476ME15%23"
			(at 298.45 82.55 0)
			(effects
				(font
					(size 1.27 1.27)
					(thickness 0.15)
				)
				(justify left bottom)
				(hide yes)
			)
		)
		(property "Description" ""
			(at 283.21 62.23 0)
			(effects
				(font
					(size 1.27 1.27)
				)
			)
		)
		(property "Manufacturer" "Murata"
			(at 303.53 82.55 0)
			(effects
				(font
					(size 1.27 1.27)
					(thickness 0.15)
				)
				(justify left bottom)
				(hide yes)
			)
		)
		(property "MPN" "GRM188R60J476ME15D"
			(at 300.99 82.55 0)
			(effects
				(font
					(size 1.27 1.27)
					(thickness 0.15)
				)
				(justify left bottom)
				(hide yes)
			)
		)
		(property "Val" "47u"
			(at 283.845 66.6877 90)
			(effects
				(font
					(size 1.27 1.27)
					(thickness 0.15)
				)
				(justify right)
			)
		)
		(property "License" "Apache-2.0"
			(at 306.07 82.55 0)
			(effects
				(font
					(size 1.27 1.27)
					(thickness 0.15)
				)
				(justify left bottom)
				(hide yes)
			)
		)
		(property "Author" "Antmicro"
			(at 308.61 82.55 0)
			(effects
				(font
					(size 1.27 1.27)
					(thickness 0.15)
				)
				(justify left bottom)
				(hide yes)
			)
		)
		(property "Voltage" ""
			(at 311.15 82.55 0)
			(effects
				(font
					(size 1.27 1.27)
				)
				(justify left bottom)
				(hide yes)
			)
		)
		(property "Dielectric" ""
			(at 313.69 82.55 0)
			(effects
				(font
					(size 1.27 1.27)
				)
				(justify left bottom)
				(hide yes)
			)
		)
		(pin "1"
		)
		(pin "2"
		)
		(instances
			(project "k410t-devboard"
				(path ""
					(reference "C107")
					(unit 1)
				)
			)
		)
	)
	(symbol
		(lib_id "antmicroCapacitors0402:C_100n_0402")
		(at 172.72 67.31 270)
		(mirror x)
		(unit 1)
		(exclude_from_sim no)
		(in_bom yes)
		(on_board yes)
		(dnp no)
		(property "Reference" "C68"
			(at 172.085 62.865 90)
			(effects
				(font
					(size 1.27 1.27)
				)
				(justify right)
			)
		)
		(property "Value" "C_100n_0402"
			(at 162.56 46.99 0)
			(effects
				(font
					(size 1.27 1.27)
					(thickness 0.15)
				)
				(justify left bottom)
				(hide yes)
			)
		)
		(property "Footprint" "antmicro-footprints:C_0402_1005Metric"
			(at 160.02 46.99 0)
			(effects
				(font
					(size 1.27 1.27)
					(thickness 0.15)
				)
				(justify left bottom)
				(hide yes)
			)
		)
		(property "Datasheet" "https://www.murata.com/products/productdetail?partno=GRM155R61H104KE14%23"
			(at 157.48 46.99 0)
			(effects
				(font
					(size 1.27 1.27)
					(thickness 0.15)
				)
				(justify left bottom)
				(hide yes)
			)
		)
		(property "Description" ""
			(at 172.72 67.31 0)
			(effects
				(font
					(size 1.27 1.27)
				)
			)
		)
		(property "Manufacturer" "Murata"
			(at 152.4 46.99 0)
			(effects
				(font
					(size 1.27 1.27)
					(thickness 0.15)
				)
				(justify left bottom)
				(hide yes)
			)
		)
		(property "MPN" "GRM155R61H104KE14D"
			(at 154.94 46.99 0)
			(effects
				(font
					(size 1.27 1.27)
					(thickness 0.15)
				)
				(justify left bottom)
				(hide yes)
			)
		)
		(property "Val" "100n"
			(at 172.085 66.675 90)
			(effects
				(font
					(size 1.27 1.27)
					(thickness 0.15)
				)
				(justify right)
			)
		)
		(property "License" "Apache-2.0"
			(at 149.86 46.99 0)
			(effects
				(font
					(size 1.27 1.27)
					(thickness 0.15)
				)
				(justify left bottom)
				(hide yes)
			)
		)
		(property "Author" "Antmicro"
			(at 147.32 46.99 0)
			(effects
				(font
					(size 1.27 1.27)
					(thickness 0.15)
				)
				(justify left bottom)
				(hide yes)
			)
		)
		(property "Voltage" "50V"
			(at 144.78 46.99 0)
			(effects
				(font
					(size 1.27 1.27)
				)
				(justify left bottom)
				(hide yes)
			)
		)
		(property "Dielectric" "X5R"
			(at 142.24 46.99 0)
			(effects
				(font
					(size 1.27 1.27)
				)
				(justify left bottom)
				(hide yes)
			)
		)
		(pin "1"
		)
		(pin "2"
		)
		(instances
			(project "k410t-devboard"
				(path ""
					(reference "C68")
					(unit 1)
				)
			)
		)
	)
	(symbol
		(lib_id "antmicroCapacitors0402:C_100n_0402")
		(at 149.86 67.31 270)
		(mirror x)
		(unit 1)
		(exclude_from_sim no)
		(in_bom yes)
		(on_board yes)
		(dnp no)
		(property "Reference" "C88"
			(at 149.225 62.865 90)
			(effects
				(font
					(size 1.27 1.27)
				)
				(justify right)
			)
		)
		(property "Value" "C_100n_0402"
			(at 139.7 46.99 0)
			(effects
				(font
					(size 1.27 1.27)
					(thickness 0.15)
				)
				(justify left bottom)
				(hide yes)
			)
		)
		(property "Footprint" "antmicro-footprints:C_0402_1005Metric"
			(at 137.16 46.99 0)
			(effects
				(font
					(size 1.27 1.27)
					(thickness 0.15)
				)
				(justify left bottom)
				(hide yes)
			)
		)
		(property "Datasheet" "https://www.murata.com/products/productdetail?partno=GRM155R61H104KE14%23"
			(at 134.62 46.99 0)
			(effects
				(font
					(size 1.27 1.27)
					(thickness 0.15)
				)
				(justify left bottom)
				(hide yes)
			)
		)
		(property "Description" ""
			(at 149.86 67.31 0)
			(effects
				(font
					(size 1.27 1.27)
				)
			)
		)
		(property "Manufacturer" "Murata"
			(at 129.54 46.99 0)
			(effects
				(font
					(size 1.27 1.27)
					(thickness 0.15)
				)
				(justify left bottom)
				(hide yes)
			)
		)
		(property "MPN" "GRM155R61H104KE14D"
			(at 132.08 46.99 0)
			(effects
				(font
					(size 1.27 1.27)
					(thickness 0.15)
				)
				(justify left bottom)
				(hide yes)
			)
		)
		(property "Val" "100n"
			(at 149.225 66.675 90)
			(effects
				(font
					(size 1.27 1.27)
					(thickness 0.15)
				)
				(justify right)
			)
		)
		(property "License" "Apache-2.0"
			(at 127 46.99 0)
			(effects
				(font
					(size 1.27 1.27)
					(thickness 0.15)
				)
				(justify left bottom)
				(hide yes)
			)
		)
		(property "Author" "Antmicro"
			(at 124.46 46.99 0)
			(effects
				(font
					(size 1.27 1.27)
					(thickness 0.15)
				)
				(justify left bottom)
				(hide yes)
			)
		)
		(property "Voltage" "50V"
			(at 121.92 46.99 0)
			(effects
				(font
					(size 1.27 1.27)
				)
				(justify left bottom)
				(hide yes)
			)
		)
		(property "Dielectric" "X5R"
			(at 119.38 46.99 0)
			(effects
				(font
					(size 1.27 1.27)
				)
				(justify left bottom)
				(hide yes)
			)
		)
		(pin "1"
		)
		(pin "2"
		)
		(instances
			(project "k410t-devboard"
				(path ""
					(reference "C88")
					(unit 1)
				)
			)
		)
	)
	(symbol
		(lib_id "antmicroCapacitors0402:C_100n_0402")
		(at 142.24 67.31 270)
		(mirror x)
		(unit 1)
		(exclude_from_sim no)
		(in_bom yes)
		(on_board yes)
		(dnp no)
		(property "Reference" "C93"
			(at 141.605 62.865 90)
			(effects
				(font
					(size 1.27 1.27)
				)
				(justify right)
			)
		)
		(property "Value" "C_100n_0402"
			(at 132.08 46.99 0)
			(effects
				(font
					(size 1.27 1.27)
					(thickness 0.15)
				)
				(justify left bottom)
				(hide yes)
			)
		)
		(property "Footprint" "antmicro-footprints:C_0402_1005Metric"
			(at 129.54 46.99 0)
			(effects
				(font
					(size 1.27 1.27)
					(thickness 0.15)
				)
				(justify left bottom)
				(hide yes)
			)
		)
		(property "Datasheet" "https://www.murata.com/products/productdetail?partno=GRM155R61H104KE14%23"
			(at 127 46.99 0)
			(effects
				(font
					(size 1.27 1.27)
					(thickness 0.15)
				)
				(justify left bottom)
				(hide yes)
			)
		)
		(property "Description" ""
			(at 142.24 67.31 0)
			(effects
				(font
					(size 1.27 1.27)
				)
			)
		)
		(property "Manufacturer" "Murata"
			(at 121.92 46.99 0)
			(effects
				(font
					(size 1.27 1.27)
					(thickness 0.15)
				)
				(justify left bottom)
				(hide yes)
			)
		)
		(property "MPN" "GRM155R61H104KE14D"
			(at 124.46 46.99 0)
			(effects
				(font
					(size 1.27 1.27)
					(thickness 0.15)
				)
				(justify left bottom)
				(hide yes)
			)
		)
		(property "Val" "100n"
			(at 141.605 66.675 90)
			(effects
				(font
					(size 1.27 1.27)
					(thickness 0.15)
				)
				(justify right)
			)
		)
		(property "License" "Apache-2.0"
			(at 119.38 46.99 0)
			(effects
				(font
					(size 1.27 1.27)
					(thickness 0.15)
				)
				(justify left bottom)
				(hide yes)
			)
		)
		(property "Author" "Antmicro"
			(at 116.84 46.99 0)
			(effects
				(font
					(size 1.27 1.27)
					(thickness 0.15)
				)
				(justify left bottom)
				(hide yes)
			)
		)
		(property "Voltage" "50V"
			(at 114.3 46.99 0)
			(effects
				(font
					(size 1.27 1.27)
				)
				(justify left bottom)
				(hide yes)
			)
		)
		(property "Dielectric" "X5R"
			(at 111.76 46.99 0)
			(effects
				(font
					(size 1.27 1.27)
				)
				(justify left bottom)
				(hide yes)
			)
		)
		(pin "1"
		)
		(pin "2"
		)
		(instances
			(project "k410t-devboard"
				(path ""
					(reference "C93")
					(unit 1)
				)
			)
		)
	)
	(symbol
		(lib_id "antmicroCapacitors0402:C_100n_0402")
		(at 260.35 67.31 90)
		(unit 1)
		(exclude_from_sim no)
		(in_bom yes)
		(on_board yes)
		(dnp no)
		(property "Reference" "C89"
			(at 260.985 62.865 90)
			(effects
				(font
					(size 1.27 1.27)
				)
				(justify right)
			)
		)
		(property "Value" "C_100n_0402"
			(at 270.51 46.99 0)
			(effects
				(font
					(size 1.27 1.27)
					(thickness 0.15)
				)
				(justify left bottom)
				(hide yes)
			)
		)
		(property "Footprint" "antmicro-footprints:C_0402_1005Metric"
			(at 273.05 46.99 0)
			(effects
				(font
					(size 1.27 1.27)
					(thickness 0.15)
				)
				(justify left bottom)
				(hide yes)
			)
		)
		(property "Datasheet" "https://www.murata.com/products/productdetail?partno=GRM155R61H104KE14%23"
			(at 275.59 46.99 0)
			(effects
				(font
					(size 1.27 1.27)
					(thickness 0.15)
				)
				(justify left bottom)
				(hide yes)
			)
		)
		(property "Description" ""
			(at 260.35 67.31 0)
			(effects
				(font
					(size 1.27 1.27)
				)
			)
		)
		(property "Manufacturer" "Murata"
			(at 280.67 46.99 0)
			(effects
				(font
					(size 1.27 1.27)
					(thickness 0.15)
				)
				(justify left bottom)
				(hide yes)
			)
		)
		(property "MPN" "GRM155R61H104KE14D"
			(at 278.13 46.99 0)
			(effects
				(font
					(size 1.27 1.27)
					(thickness 0.15)
				)
				(justify left bottom)
				(hide yes)
			)
		)
		(property "Val" "100n"
			(at 260.985 66.675 90)
			(effects
				(font
					(size 1.27 1.27)
					(thickness 0.15)
				)
				(justify right)
			)
		)
		(property "License" "Apache-2.0"
			(at 283.21 46.99 0)
			(effects
				(font
					(size 1.27 1.27)
					(thickness 0.15)
				)
				(justify left bottom)
				(hide yes)
			)
		)
		(property "Author" "Antmicro"
			(at 285.75 46.99 0)
			(effects
				(font
					(size 1.27 1.27)
					(thickness 0.15)
				)
				(justify left bottom)
				(hide yes)
			)
		)
		(property "Voltage" "50V"
			(at 288.29 46.99 0)
			(effects
				(font
					(size 1.27 1.27)
				)
				(justify left bottom)
				(hide yes)
			)
		)
		(property "Dielectric" "X5R"
			(at 290.83 46.99 0)
			(effects
				(font
					(size 1.27 1.27)
				)
				(justify left bottom)
				(hide yes)
			)
		)
		(pin "1"
		)
		(pin "2"
		)
		(instances
			(project "k410t-devboard"
				(path ""
					(reference "C89")
					(unit 1)
				)
			)
		)
	)
	(symbol
		(lib_id "antmicroCapacitors0603:C_47u_0603")
		(at 127 62.23 270)
		(unit 1)
		(exclude_from_sim no)
		(in_bom yes)
		(on_board yes)
		(dnp no)
		(property "Reference" "C106"
			(at 126.365 62.8777 90)
			(effects
				(font
					(size 1.27 1.27)
				)
				(justify right)
			)
		)
		(property "Value" "C_47u_0603"
			(at 116.84 82.55 0)
			(effects
				(font
					(size 1.27 1.27)
					(thickness 0.15)
				)
				(justify left bottom)
				(hide yes)
			)
		)
		(property "Footprint" "antmicro-footprints:C_0603_1608Metric"
			(at 114.3 82.55 0)
			(effects
				(font
					(size 1.27 1.27)
					(thickness 0.15)
				)
				(justify left bottom)
				(hide yes)
			)
		)
		(property "Datasheet" "https://www.murata.com/products/productdetail?partno=GRM188R60J476ME15%23"
			(at 111.76 82.55 0)
			(effects
				(font
					(size 1.27 1.27)
					(thickness 0.15)
				)
				(justify left bottom)
				(hide yes)
			)
		)
		(property "Description" ""
			(at 127 62.23 0)
			(effects
				(font
					(size 1.27 1.27)
				)
			)
		)
		(property "Manufacturer" "Murata"
			(at 106.68 82.55 0)
			(effects
				(font
					(size 1.27 1.27)
					(thickness 0.15)
				)
				(justify left bottom)
				(hide yes)
			)
		)
		(property "MPN" "GRM188R60J476ME15D"
			(at 109.22 82.55 0)
			(effects
				(font
					(size 1.27 1.27)
					(thickness 0.15)
				)
				(justify left bottom)
				(hide yes)
			)
		)
		(property "Val" "47u"
			(at 126.365 66.6877 90)
			(effects
				(font
					(size 1.27 1.27)
					(thickness 0.15)
				)
				(justify right)
			)
		)
		(property "License" "Apache-2.0"
			(at 104.14 82.55 0)
			(effects
				(font
					(size 1.27 1.27)
					(thickness 0.15)
				)
				(justify left bottom)
				(hide yes)
			)
		)
		(property "Author" "Antmicro"
			(at 101.6 82.55 0)
			(effects
				(font
					(size 1.27 1.27)
					(thickness 0.15)
				)
				(justify left bottom)
				(hide yes)
			)
		)
		(property "Voltage" ""
			(at 99.06 82.55 0)
			(effects
				(font
					(size 1.27 1.27)
				)
				(justify left bottom)
				(hide yes)
			)
		)
		(property "Dielectric" ""
			(at 96.52 82.55 0)
			(effects
				(font
					(size 1.27 1.27)
				)
				(justify left bottom)
				(hide yes)
			)
		)
		(pin "1"
		)
		(pin "2"
		)
		(instances
			(project "k410t-devboard"
				(path ""
					(reference "C106")
					(unit 1)
				)
			)
		)
	)
	(symbol
		(lib_id "antmicropower:GND")
		(at 283.21 71.12 0)
		(mirror y)
		(unit 1)
		(exclude_from_sim no)
		(in_bom yes)
		(on_board yes)
		(dnp no)
		(property "Reference" "#PWR025"
			(at 283.21 77.47 0)
			(effects
				(font
					(size 1.27 1.27)
				)
				(hide yes)
			)
		)
		(property "Value" "GND"
			(at 283.21 74.93 0)
			(effects
				(font
					(size 1.27 1.27)
				)
			)
		)
		(property "Footprint" ""
			(at 274.32 78.74 0)
			(effects
				(font
					(size 1.27 1.27)
					(thickness 0.15)
				)
				(justify left bottom)
				(hide yes)
			)
		)
		(property "Datasheet" ""
			(at 274.32 83.82 0)
			(effects
				(font
					(size 1.27 1.27)
					(thickness 0.15)
				)
				(justify left bottom)
				(hide yes)
			)
		)
		(property "Description" ""
			(at 283.21 71.12 0)
			(effects
				(font
					(size 1.27 1.27)
				)
			)
		)
		(property "Author" "Antmicro"
			(at 274.32 78.74 0)
			(effects
				(font
					(size 1.27 1.27)
					(thickness 0.15)
				)
				(justify left bottom)
				(hide yes)
			)
		)
		(property "License" "Apache-2.0"
			(at 274.32 81.28 0)
			(effects
				(font
					(size 1.27 1.27)
					(thickness 0.15)
				)
				(justify left bottom)
				(hide yes)
			)
		)
		(pin "1"
		)
		(instances
			(project "k410t-devboard"
				(path ""
					(reference "#PWR025")
					(unit 1)
				)
			)
		)
	)
)
